FILE_TYPE = MACRO_DRAWING;
SET COLOR_WIRE YELLOW;
SET COLOR_PROP MONO;
SET COLOR_DOT WHITE;
SET COLOR_ARC YELLOW;
SET COLOR_BODY GREEN;
SET COLOR_NOTE MONO;
SET PROP_DISPLAY VALUE;
SET PAGE_NUMBER P102;
FORCEADD NB3W1200L..1
(350 2975);
FORCEPROP 2 LASTPIN (-300 2175) $PN 5
J 2
(-310 2185);
DISPLAY 0.617021 (-310 2185);
PAINT ORANGE (-310 2185);
FORCEPROP 2 LASTPIN (-300 2075) $PN 4
J 2
(-310 2085);
DISPLAY 0.617021 (-310 2085);
PAINT ORANGE (-310 2085);
FORCEPROP 2 LASTPIN (-300 2275) $PN 6
J 2
(-310 2285);
DISPLAY 0.617021 (-310 2285);
PAINT ORANGE (-310 2285);
FORCEPROP 2 LASTPIN (-300 2425) $PN 9
J 2
(-310 2435);
DISPLAY 0.617021 (-310 2435);
PAINT ORANGE (-310 2435);
FORCEPROP 2 LASTPIN (-300 2375) $PN 10
J 2
(-310 2385);
DISPLAY 0.617021 (-310 2385);
PAINT ORANGE (-310 2385);
FORCEPROP 2 LASTPIN (-300 2525) $PN 19
J 2
(-310 2535);
DISPLAY 0.617021 (-310 2535);
PAINT ORANGE (-310 2535);
FORCEPROP 2 LASTPIN (-300 2625) $PN 28
J 2
(-310 2635);
DISPLAY 0.617021 (-310 2635);
PAINT ORANGE (-310 2635);
FORCEPROP 2 LASTPIN (-300 2575) $PN 20
J 2
(-310 2585);
DISPLAY 0.617021 (-310 2585);
PAINT ORANGE (-310 2585);
FORCEPROP 2 LASTPIN (-300 2675) $PN 29
J 2
(-310 2685);
DISPLAY 0.617021 (-310 2685);
PAINT ORANGE (-310 2685);
FORCEPROP 2 LASTPIN (-300 2725) $PN 36
J 2
(-310 2735);
DISPLAY 0.617021 (-310 2735);
PAINT ORANGE (-310 2735);
FORCEPROP 2 LASTPIN (-300 2775) $PN 37
J 2
(-310 2785);
DISPLAY 0.617021 (-310 2785);
PAINT ORANGE (-310 2785);
FORCEPROP 2 LASTPIN (-300 2875) $PN 45
J 2
(-310 2885);
DISPLAY 0.617021 (-310 2885);
PAINT ORANGE (-310 2885);
FORCEPROP 2 LASTPIN (-300 2825) $PN 44
J 2
(-310 2835);
DISPLAY 0.617021 (-310 2835);
PAINT ORANGE (-310 2835);
FORCEPROP 2 LASTPIN (-300 2925) $PN 52
J 2
(-310 2935);
DISPLAY 0.617021 (-310 2935);
PAINT ORANGE (-310 2935);
FORCEPROP 2 LASTPIN (-300 2975) $PN 53
J 2
(-310 2985);
DISPLAY 0.617021 (-310 2985);
PAINT ORANGE (-310 2985);
FORCEPROP 2 LASTPIN (-300 3025) $PN 61
J 2
(-310 3035);
DISPLAY 0.617021 (-310 3035);
PAINT ORANGE (-310 3035);
FORCEPROP 2 LASTPIN (-300 3225) $PN 12
J 2
(-310 3235);
DISPLAY 0.617021 (-310 3235);
PAINT ORANGE (-310 3235);
FORCEPROP 2 LASTPIN (-300 3175) $PN 13
J 2
(-310 3185);
DISPLAY 0.617021 (-310 3185);
PAINT ORANGE (-310 3185);
FORCEPROP 2 LASTPIN (-300 3075) $PN 62
J 2
(-310 3085);
DISPLAY 0.617021 (-310 3085);
PAINT ORANGE (-310 3085);
FORCEPROP 2 LASTPIN (-300 3475) $PN 8
J 2
(-310 3485);
DISPLAY 0.617021 (-310 3485);
PAINT ORANGE (-310 3485);
FORCEPROP 2 LASTPIN (-300 3525) $PN 25
J 2
(-310 3535);
DISPLAY 0.617021 (-310 3535);
PAINT ORANGE (-310 3535);
FORCEPROP 2 LASTPIN (-300 3325) $PN 14
J 2
(-310 3335);
DISPLAY 0.617021 (-310 3335);
PAINT ORANGE (-310 3335);
FORCEPROP 2 LASTPIN (-300 3375) $PN 11
J 2
(-310 3385);
DISPLAY 0.617021 (-310 3385);
PAINT ORANGE (-310 3385);
FORCEPROP 2 LASTPIN (-300 3725) $PN 24
J 2
(-310 3735);
DISPLAY 0.617021 (-310 3735);
PAINT ORANGE (-310 3735);
FORCEPROP 2 LASTPIN (-300 3775) $PN 40
J 2
(-310 3785);
DISPLAY 0.617021 (-310 3785);
PAINT ORANGE (-310 3785);
FORCEPROP 2 LASTPIN (-300 3675) $PN 56
J 2
(-310 3685);
DISPLAY 0.617021 (-310 3685);
PAINT ORANGE (-310 3685);
FORCEPROP 2 LASTPIN (-300 3575) $PN 32
J 2
(-310 3585);
DISPLAY 0.617021 (-310 3585);
PAINT ORANGE (-310 3585);
FORCEPROP 2 LASTPIN (-300 3625) $PN 49
J 2
(-310 3635);
DISPLAY 0.617021 (-310 3635);
PAINT ORANGE (-310 3635);
FORCEPROP 2 LASTPIN (-300 3825) $PN 57
J 2
(-310 3835);
DISPLAY 0.617021 (-310 3835);
PAINT ORANGE (-310 3835);
FORCEPROP 2 LASTPIN (-300 3875) $PN 1
J 2
(-310 3885);
DISPLAY 0.617021 (-310 3885);
PAINT ORANGE (-310 3885);
FORCEPROP 1 LAST MATERIAL IC
J 0
(-250 4025);
DISPLAY 0.617021 (-250 4025);
PAINT SKYBLUE (-250 4025);
FORCEPROP 1 LAST LOCATION EU4D2
J 0
(-250 4075);
DISPLAY 0.617021 (-250 4075);
PAINT AQUA (-250 4075);
FORCEPROP 1 LAST PART_NUMBER H13585-001
J 0
(-250 1925);
DISPLAY 0.617021 (-250 1925);
PAINT BLUE (-250 1925);
FORCEPROP 2 LASTPIN (1000 2025) $PN 65
J 0
(1010 2035);
DISPLAY 0.617021 (1010 2035);
PAINT ORANGE (1010 2035);
FORCEPROP 2 LASTPIN (1000 2525) $PN 18
J 0
(1010 2535);
DISPLAY 0.617021 (1010 2535);
PAINT ORANGE (1010 2535);
FORCEPROP 2 LASTPIN (1000 2575) $PN 17
J 0
(1010 2585);
DISPLAY 0.617021 (1010 2585);
PAINT ORANGE (1010 2585);
FORCEPROP 2 LASTPIN (1000 2625) $PN 22
J 0
(1010 2635);
DISPLAY 0.617021 (1010 2635);
PAINT ORANGE (1010 2635);
FORCEPROP 2 LASTPIN (1000 2675) $PN 21
J 0
(1010 2685);
DISPLAY 0.617021 (1010 2685);
PAINT ORANGE (1010 2685);
FORCEPROP 2 LASTPIN (1000 2725) $PN 27
J 0
(1010 2735);
DISPLAY 0.617021 (1010 2735);
PAINT ORANGE (1010 2735);
FORCEPROP 2 LASTPIN (1000 2775) $PN 26
J 0
(1010 2785);
DISPLAY 0.617021 (1010 2785);
PAINT ORANGE (1010 2785);
FORCEPROP 2 LASTPIN (1000 2825) $PN 31
J 0
(1010 2835);
DISPLAY 0.617021 (1010 2835);
PAINT ORANGE (1010 2835);
FORCEPROP 2 LASTPIN (1000 2875) $PN 30
J 0
(1010 2885);
DISPLAY 0.617021 (1010 2885);
PAINT ORANGE (1010 2885);
FORCEPROP 2 LASTPIN (1000 2925) $PN 35
J 0
(1010 2935);
DISPLAY 0.617021 (1010 2935);
PAINT ORANGE (1010 2935);
FORCEPROP 2 LASTPIN (1000 2975) $PN 34
J 0
(1010 2985);
DISPLAY 0.617021 (1010 2985);
PAINT ORANGE (1010 2985);
FORCEPROP 2 LASTPIN (1000 3025) $PN 39
J 0
(1010 3035);
DISPLAY 0.617021 (1010 3035);
PAINT ORANGE (1010 3035);
FORCEPROP 2 LASTPIN (1000 3075) $PN 38
J 0
(1010 3085);
DISPLAY 0.617021 (1010 3085);
PAINT ORANGE (1010 3085);
FORCEPROP 2 LASTPIN (1000 3125) $PN 43
J 0
(1010 3135);
DISPLAY 0.617021 (1010 3135);
PAINT ORANGE (1010 3135);
FORCEPROP 2 LASTPIN (1000 3175) $PN 42
J 0
(1010 3185);
DISPLAY 0.617021 (1010 3185);
PAINT ORANGE (1010 3185);
FORCEPROP 2 LASTPIN (1000 3225) $PN 47
J 0
(1010 3235);
DISPLAY 0.617021 (1010 3235);
PAINT ORANGE (1010 3235);
FORCEPROP 2 LASTPIN (1000 3275) $PN 46
J 0
(1010 3285);
DISPLAY 0.617021 (1010 3285);
PAINT ORANGE (1010 3285);
FORCEPROP 2 LASTPIN (1000 3325) $PN 51
J 0
(1010 3335);
DISPLAY 0.617021 (1010 3335);
PAINT ORANGE (1010 3335);
FORCEPROP 2 LASTPIN (1000 3375) $PN 50
J 0
(1010 3385);
DISPLAY 0.617021 (1010 3385);
PAINT ORANGE (1010 3385);
FORCEPROP 2 LASTPIN (1000 3425) $PN 55
J 0
(1010 3435);
DISPLAY 0.617021 (1010 3435);
PAINT ORANGE (1010 3435);
FORCEPROP 2 LASTPIN (1000 3475) $PN 54
J 0
(1010 3485);
DISPLAY 0.617021 (1010 3485);
PAINT ORANGE (1010 3485);
FORCEPROP 2 LASTPIN (1000 3525) $PN 60
J 0
(1010 3535);
DISPLAY 0.617021 (1010 3535);
PAINT ORANGE (1010 3535);
FORCEPROP 2 LASTPIN (1000 3575) $PN 59
J 0
(1010 3585);
DISPLAY 0.617021 (1010 3585);
PAINT ORANGE (1010 3585);
FORCEPROP 2 LASTPIN (1000 3625) $PN 64
J 0
(1010 3635);
DISPLAY 0.617021 (1010 3635);
PAINT ORANGE (1010 3635);
FORCEPROP 2 LASTPIN (1000 3675) $PN 63
J 0
(1010 3685);
DISPLAY 0.617021 (1010 3685);
PAINT ORANGE (1010 3685);
FORCEPROP 2 LASTPIN (1000 2075) $PN 7
J 0
(1010 2085);
DISPLAY 0.617021 (1010 2085);
PAINT ORANGE (1010 2085);
FORCEPROP 2 LASTPIN (1000 2125) $PN 23
J 0
(1010 2135);
DISPLAY 0.617021 (1010 2135);
PAINT ORANGE (1010 2135);
FORCEPROP 2 LASTPIN (1000 2175) $PN 33
J 0
(1010 2185);
DISPLAY 0.617021 (1010 2185);
PAINT ORANGE (1010 2185);
FORCEPROP 2 LASTPIN (1000 2225) $PN 41
J 0
(1010 2235);
DISPLAY 0.617021 (1010 2235);
PAINT ORANGE (1010 2235);
FORCEPROP 2 LASTPIN (1000 2275) $PN 48
J 0
(1010 2285);
DISPLAY 0.617021 (1010 2285);
PAINT ORANGE (1010 2285);
FORCEPROP 2 LASTPIN (1000 2325) $PN 58
J 0
(1010 2335);
DISPLAY 0.617021 (1010 2335);
PAINT ORANGE (1010 2335);
FORCEPROP 2 LASTPIN (1000 2375) $PN 2
J 0
(1010 2385);
DISPLAY 0.617021 (1010 2385);
PAINT ORANGE (1010 2385);
FORCEPROP 2 LASTPIN (1000 3775) $PN 3
J 0
(1010 3785);
DISPLAY 0.617021 (1010 3785);
PAINT ORANGE (1010 3785);
FORCEPROP 2 LASTPIN (1000 3825) $PN 16
J 0
(1010 3835);
DISPLAY 0.617021 (1010 3835);
PAINT ORANGE (1010 3835);
FORCEPROP 2 LASTPIN (1000 3875) $PN 15
J 0
(1010 3885);
DISPLAY 0.617021 (1010 3885);
PAINT ORANGE (1010 3885);
FORCEPROP 2 LAST CDS_LOCATION EU4D2
J 0
(-250 4075);
DISPLAY 0.617021 (-250 4075);
PAINT AQUA (-250 4075);
DISPLAY INVISIBLE (-250 4075);
FORCEPROP 2 LAST ROOM DB1200ZL
J 0
(-250 4175);
DISPLAY 1.021277 (-250 4175);
PAINT ORANGE (-250 4175);
DISPLAY INVISIBLE (-250 4175);
FORCEPROP 2 LAST SEC 1
J 0
(-250 4125);
DISPLAY 0.680851 (-250 4125);
PAINT MONO (-250 4125);
DISPLAY INVISIBLE (-250 4125);
FORCEPROP 2 LAST SEC_TYPE LCC
J 0
(-250 4125);
DISPLAY 1.021277 (-250 4125);
PAINT ORANGE (-250 4125);
DISPLAY INVISIBLE (-250 4125);
FORCEPROP 2 LAST BOM_COST SYS_CLOCK
J 0
(-250 4275);
DISPLAY 1.021277 (-250 4275);
PAINT ORANGE (-250 4275);
DISPLAY INVISIBLE (-250 4275);
FORCEPROP 1 LAST PACK_TYPE LCC
J 0
(-250 4125);
PAINT SKYBLUE (-250 4125);
DISPLAY INVISIBLE (-250 4125);
FORCEPROP 2 LAST CDS_LIB mstr_clock
J 0
(350 2975);
PAINT MONO (350 2975);
DISPLAY INVISIBLE (350 2975);
FORCEPROP 1 LAST CDS_LMAN_SYM_OUTLINE -600,1000,600,-1000
J 0
(350 2975);
DISPLAY 0.468085 (350 2975);
PAINT GREEN (350 2975);
DISPLAY INVISIBLE (350 2975);
FORCEPROP 1 LAST PATH I1
J 0
(350 4025);
PAINT GREEN (350 4025);
DISPLAY INVISIBLE (350 4025);
FORCEADD CAP..1
(1975 975);
FORCEPROP 1 LASTPIN (1975 875) $PN 2
J 0
(1985 855);
DISPLAY 0.617021 (1985 855);
PAINT ORANGE (1985 855);
FORCEPROP 1 LASTPIN (1975 1075) $PN 1
J 0
(1985 1055);
DISPLAY 0.617021 (1985 1055);
PAINT ORANGE (1985 1055);
FORCEPROP 1 LAST MATERIAL X7R
J 0
(2025 875);
DISPLAY 0.617021 (2025 875);
PAINT SKYBLUE (2025 875);
FORCEPROP 1 LAST VOLTAGE 16V
J 0
(2025 975);
DISPLAY 0.617021 (2025 975);
PAINT SKYBLUE (2025 975);
FORCEPROP 1 LAST PACK_TYPE 0805
J 0
(2025 775);
DISPLAY 0.617021 (2025 775);
PAINT SKYBLUE (2025 775);
FORCEPROP 1 LAST TOLERANCE 10%
J 0
(2025 925);
DISPLAY 0.617021 (2025 925);
PAINT SKYBLUE (2025 925);
FORCEPROP 1 LAST VALUE 10UF
J 0
(2025 1025);
DISPLAY 0.617021 (2025 1025);
PAINT SKYBLUE (2025 1025);
FORCEPROP 1 LAST PART_NUMBER G10601-001
J 0
(2025 825);
DISPLAY 0.617021 (2025 825);
PAINT BLUE (2025 825);
FORCEPROP 1 LAST LOCATION C3D22
J 0
(2025 1075);
DISPLAY 0.617021 (2025 1075);
PAINT AQUA (2025 1075);
FORCEPROP 2 LAST CDS_LIB mstr_discrete
J 0
(1975 975);
PAINT ORANGE (1975 975);
DISPLAY INVISIBLE (1975 975);
FORCEPROP 2 LAST ROOM DB1200ZL
J 0
(2025 1175);
DISPLAY 1.021277 (2025 1175);
PAINT ORANGE (2025 1175);
DISPLAY INVISIBLE (2025 1175);
FORCEPROP 1 LAST PATH I10
J 0
(2025 1125);
DISPLAY 0.978723 (2025 1125);
PAINT WHITE (2025 1125);
DISPLAY INVISIBLE (2025 1125);
FORCEPROP 2 LAST CDS_LOCATION C3D22
J 0
(2025 1075);
DISPLAY 0.617021 (2025 1075);
PAINT AQUA (2025 1075);
DISPLAY INVISIBLE (2025 1075);
FORCEPROP 2 LAST SEC 1
J 0
(2025 1175);
DISPLAY 0.680851 (2025 1175);
PAINT MONO (2025 1175);
DISPLAY INVISIBLE (2025 1175);
FORCEPROP 2 LAST SEC_TYPE 0805
J 0
(2025 1175);
DISPLAY 1.021277 (2025 1175);
PAINT ORANGE (2025 1175);
DISPLAY INVISIBLE (2025 1175);
FORCEPROP 2 LAST BOM_COST SYS_CLOCK
J 0
(2025 1275);
DISPLAY 1.021277 (2025 1275);
PAINT ORANGE (2025 1275);
DISPLAY INVISIBLE (2025 1275);
FORCEADD CAP_A..1
(2575 975);
FORCEPROP 1 LAST TOLERANCE 10%
J 0
(2625 925);
DISPLAY 0.617021 (2625 925);
PAINT SKYBLUE (2625 925);
FORCEPROP 1 LAST PACK_TYPE 0402V
J 0
(2625 775);
DISPLAY 0.617021 (2625 775);
PAINT SKYBLUE (2625 775);
FORCEPROP 1 LAST VOLTAGE 16V
J 0
(2625 975);
DISPLAY 0.617021 (2625 975);
PAINT SKYBLUE (2625 975);
FORCEPROP 1 LAST MATERIAL X7R
J 0
(2625 875);
DISPLAY 0.617021 (2625 875);
PAINT SKYBLUE (2625 875);
FORCEPROP 1 LASTPIN (2575 875) $PN 2
J 0
(2585 855);
DISPLAY 0.617021 (2585 855);
PAINT ORANGE (2585 855);
FORCEPROP 1 LAST PART_NUMBER A36096-030
J 0
(2625 825);
DISPLAY 0.617021 (2625 825);
PAINT BLUE (2625 825);
FORCEPROP 1 LASTPIN (2575 1075) $PN 1
J 0
(2585 1055);
DISPLAY 0.617021 (2585 1055);
PAINT ORANGE (2585 1055);
FORCEPROP 1 LAST VALUE 0.1UF
J 0
(2625 1025);
DISPLAY 0.617021 (2625 1025);
PAINT SKYBLUE (2625 1025);
FORCEPROP 1 LAST LOCATION C6P4
J 0
(2625 1075);
DISPLAY 0.617021 (2625 1075);
PAINT AQUA (2625 1075);
FORCEPROP 2 LAST CDS_LIB dev_discrete
J 0
(2575 975);
PAINT ORANGE (2575 975);
DISPLAY INVISIBLE (2575 975);
FORCEPROP 2 LAST CDS_LOCATION C6P4
J 0
(2625 1075);
DISPLAY 0.617021 (2625 1075);
PAINT AQUA (2625 1075);
DISPLAY INVISIBLE (2625 1075);
FORCEPROP 1 LAST PATH I11
J 0
(2625 1125);
DISPLAY 0.978723 (2625 1125);
PAINT WHITE (2625 1125);
DISPLAY INVISIBLE (2625 1125);
FORCEPROP 2 LAST CDS_SEC 1
J 0
(2625 1125);
PAINT ORANGE (2625 1125);
DISPLAY INVISIBLE (2625 1125);
FORCEPROP 2 LAST ROOM DB1200ZL
J 0
(2625 1175);
DISPLAY 1.021277 (2625 1175);
PAINT ORANGE (2625 1175);
DISPLAY INVISIBLE (2625 1175);
FORCEPROP 2 LAST SEC_TYPE 0402V
J 0
(2625 1175);
DISPLAY 1.021277 (2625 1175);
PAINT ORANGE (2625 1175);
DISPLAY INVISIBLE (2625 1175);
FORCEPROP 2 LAST SEC 1
J 0
(2625 1175);
DISPLAY 0.680851 (2625 1175);
PAINT MONO (2625 1175);
DISPLAY INVISIBLE (2625 1175);
FORCEPROP 2 LAST BOM_COST SYS_CLOCK
J 0
(2625 1275);
DISPLAY 1.021277 (2625 1275);
PAINT ORANGE (2625 1275);
DISPLAY INVISIBLE (2625 1275);
FORCEADD CAP_A..1
(2825 975);
FORCEPROP 1 LAST TOLERANCE 10%
J 0
(2875 925);
DISPLAY 0.617021 (2875 925);
PAINT SKYBLUE (2875 925);
FORCEPROP 1 LAST PACK_TYPE 0402V
J 0
(2875 775);
DISPLAY 0.617021 (2875 775);
PAINT SKYBLUE (2875 775);
FORCEPROP 1 LAST VOLTAGE 16V
J 0
(2875 975);
DISPLAY 0.617021 (2875 975);
PAINT SKYBLUE (2875 975);
FORCEPROP 1 LAST MATERIAL X7R
J 0
(2875 875);
DISPLAY 0.617021 (2875 875);
PAINT SKYBLUE (2875 875);
FORCEPROP 1 LASTPIN (2825 875) $PN 2
J 0
(2835 855);
DISPLAY 0.617021 (2835 855);
PAINT ORANGE (2835 855);
FORCEPROP 1 LASTPIN (2825 1075) $PN 1
J 0
(2835 1055);
DISPLAY 0.617021 (2835 1055);
PAINT ORANGE (2835 1055);
FORCEPROP 1 LAST VALUE 0.1UF
J 0
(2875 1025);
DISPLAY 0.617021 (2875 1025);
PAINT SKYBLUE (2875 1025);
FORCEPROP 1 LAST LOCATION C6P6
J 0
(2875 1075);
DISPLAY 0.617021 (2875 1075);
PAINT AQUA (2875 1075);
FORCEPROP 1 LAST PART_NUMBER A36096-030
J 0
(2875 825);
DISPLAY 0.617021 (2875 825);
PAINT BLUE (2875 825);
FORCEPROP 2 LAST CDS_LIB dev_discrete
J 0
(2825 975);
PAINT ORANGE (2825 975);
DISPLAY INVISIBLE (2825 975);
FORCEPROP 2 LAST SEC 1
J 0
(2875 1175);
DISPLAY 0.680851 (2875 1175);
PAINT MONO (2875 1175);
DISPLAY INVISIBLE (2875 1175);
FORCEPROP 2 LAST SEC_TYPE 0402V
J 0
(2875 1175);
DISPLAY 1.021277 (2875 1175);
PAINT ORANGE (2875 1175);
DISPLAY INVISIBLE (2875 1175);
FORCEPROP 2 LAST CDS_SEC 1
J 0
(2875 1125);
PAINT ORANGE (2875 1125);
DISPLAY INVISIBLE (2875 1125);
FORCEPROP 2 LAST CDS_LOCATION C6P6
J 0
(2875 1075);
DISPLAY 0.617021 (2875 1075);
PAINT AQUA (2875 1075);
DISPLAY INVISIBLE (2875 1075);
FORCEPROP 2 LAST ROOM DB1200ZL
J 0
(2875 1175);
DISPLAY 1.021277 (2875 1175);
PAINT ORANGE (2875 1175);
DISPLAY INVISIBLE (2875 1175);
FORCEPROP 1 LAST PATH I12
J 0
(2875 1125);
DISPLAY 0.978723 (2875 1125);
PAINT WHITE (2875 1125);
DISPLAY INVISIBLE (2875 1125);
FORCEPROP 2 LAST BOM_COST SYS_CLOCK
J 0
(2875 1275);
DISPLAY 1.021277 (2875 1275);
PAINT ORANGE (2875 1275);
DISPLAY INVISIBLE (2875 1275);
FORCEADD CAP_A..1
(3050 975);
FORCEPROP 1 LASTPIN (3050 875) $PN 2
J 0
(3060 855);
DISPLAY 0.617021 (3060 855);
PAINT ORANGE (3060 855);
FORCEPROP 1 LASTPIN (3050 1075) $PN 1
J 0
(3060 1055);
DISPLAY 0.617021 (3060 1055);
PAINT ORANGE (3060 1055);
FORCEPROP 1 LAST TOLERANCE 10%
J 0
(3100 925);
DISPLAY 0.617021 (3100 925);
PAINT SKYBLUE (3100 925);
FORCEPROP 1 LAST PACK_TYPE 0402V
J 0
(3100 775);
DISPLAY 0.617021 (3100 775);
PAINT SKYBLUE (3100 775);
FORCEPROP 1 LAST VOLTAGE 16V
J 0
(3100 975);
DISPLAY 0.617021 (3100 975);
PAINT SKYBLUE (3100 975);
FORCEPROP 1 LAST MATERIAL X7R
J 0
(3100 875);
DISPLAY 0.617021 (3100 875);
PAINT SKYBLUE (3100 875);
FORCEPROP 1 LAST PART_NUMBER A36096-030
J 0
(3100 825);
DISPLAY 0.617021 (3100 825);
PAINT BLUE (3100 825);
FORCEPROP 1 LAST LOCATION C6P10
J 0
(3100 1075);
DISPLAY 0.617021 (3100 1075);
PAINT AQUA (3100 1075);
FORCEPROP 1 LAST VALUE 0.1UF
J 0
(3100 1025);
DISPLAY 0.617021 (3100 1025);
PAINT SKYBLUE (3100 1025);
FORCEPROP 2 LAST CDS_LIB dev_discrete
J 0
(3050 975);
PAINT ORANGE (3050 975);
DISPLAY INVISIBLE (3050 975);
FORCEPROP 2 LAST SEC 1
J 0
(3100 1175);
DISPLAY 0.680851 (3100 1175);
PAINT MONO (3100 1175);
DISPLAY INVISIBLE (3100 1175);
FORCEPROP 2 LAST CDS_SEC 1
J 0
(3100 1125);
PAINT ORANGE (3100 1125);
DISPLAY INVISIBLE (3100 1125);
FORCEPROP 2 LAST CDS_LOCATION C6P10
J 0
(3100 1075);
DISPLAY 0.617021 (3100 1075);
PAINT AQUA (3100 1075);
DISPLAY INVISIBLE (3100 1075);
FORCEPROP 2 LAST ROOM DB1200ZL
J 0
(3100 1175);
DISPLAY 1.021277 (3100 1175);
PAINT ORANGE (3100 1175);
DISPLAY INVISIBLE (3100 1175);
FORCEPROP 1 LAST PATH I13
J 0
(3100 1125);
DISPLAY 0.978723 (3100 1125);
PAINT WHITE (3100 1125);
DISPLAY INVISIBLE (3100 1125);
FORCEPROP 2 LAST SEC_TYPE 0402V
J 0
(3100 1175);
DISPLAY 1.021277 (3100 1175);
PAINT ORANGE (3100 1175);
DISPLAY INVISIBLE (3100 1175);
FORCEPROP 2 LAST BOM_COST SYS_CLOCK
J 0
(3100 1275);
DISPLAY 1.021277 (3100 1275);
PAINT ORANGE (3100 1275);
DISPLAY INVISIBLE (3100 1275);
FORCEADD CAP_A..1
(3275 975);
FORCEPROP 1 LASTPIN (3275 875) $PN 2
J 0
(3285 855);
DISPLAY 0.617021 (3285 855);
PAINT ORANGE (3285 855);
FORCEPROP 1 LAST MATERIAL X7R
J 0
(3325 875);
DISPLAY 0.617021 (3325 875);
PAINT SKYBLUE (3325 875);
FORCEPROP 1 LAST VOLTAGE 16V
J 0
(3325 975);
DISPLAY 0.617021 (3325 975);
PAINT SKYBLUE (3325 975);
FORCEPROP 1 LAST PACK_TYPE 0402V
J 0
(3325 775);
DISPLAY 0.617021 (3325 775);
PAINT SKYBLUE (3325 775);
FORCEPROP 1 LAST TOLERANCE 10%
J 0
(3325 925);
DISPLAY 0.617021 (3325 925);
PAINT SKYBLUE (3325 925);
FORCEPROP 1 LAST PART_NUMBER A36096-030
J 0
(3325 825);
DISPLAY 0.617021 (3325 825);
PAINT BLUE (3325 825);
FORCEPROP 1 LASTPIN (3275 1075) $PN 1
J 0
(3285 1055);
DISPLAY 0.617021 (3285 1055);
PAINT ORANGE (3285 1055);
FORCEPROP 1 LAST VALUE 0.1UF
J 0
(3325 1025);
DISPLAY 0.617021 (3325 1025);
PAINT SKYBLUE (3325 1025);
FORCEPROP 1 LAST LOCATION C6P5
J 0
(3325 1075);
DISPLAY 0.617021 (3325 1075);
PAINT AQUA (3325 1075);
FORCEPROP 2 LAST CDS_LIB dev_discrete
J 0
(3275 975);
PAINT ORANGE (3275 975);
DISPLAY INVISIBLE (3275 975);
FORCEPROP 2 LAST CDS_LOCATION C6P5
J 0
(3325 1075);
DISPLAY 0.617021 (3325 1075);
PAINT AQUA (3325 1075);
DISPLAY INVISIBLE (3325 1075);
FORCEPROP 1 LAST PATH I14
J 0
(3325 1125);
DISPLAY 0.978723 (3325 1125);
PAINT WHITE (3325 1125);
DISPLAY INVISIBLE (3325 1125);
FORCEPROP 2 LAST CDS_SEC 1
J 0
(3325 1125);
PAINT ORANGE (3325 1125);
DISPLAY INVISIBLE (3325 1125);
FORCEPROP 2 LAST ROOM DB1200ZL
J 0
(3325 1175);
DISPLAY 1.021277 (3325 1175);
PAINT ORANGE (3325 1175);
DISPLAY INVISIBLE (3325 1175);
FORCEPROP 2 LAST SEC_TYPE 0402V
J 0
(3325 1175);
DISPLAY 1.021277 (3325 1175);
PAINT ORANGE (3325 1175);
DISPLAY INVISIBLE (3325 1175);
FORCEPROP 2 LAST SEC 1
J 0
(3325 1175);
DISPLAY 0.680851 (3325 1175);
PAINT MONO (3325 1175);
DISPLAY INVISIBLE (3325 1175);
FORCEPROP 2 LAST BOM_COST SYS_CLOCK
J 0
(3325 1275);
DISPLAY 1.021277 (3325 1275);
PAINT ORANGE (3325 1275);
DISPLAY INVISIBLE (3325 1275);
FORCEADD CAP_A..1
(3475 975);
FORCEPROP 1 LASTPIN (3475 875) $PN 2
J 0
(3485 855);
DISPLAY 0.617021 (3485 855);
PAINT ORANGE (3485 855);
FORCEPROP 1 LAST MATERIAL X7R
J 0
(3525 875);
DISPLAY 0.617021 (3525 875);
PAINT SKYBLUE (3525 875);
FORCEPROP 1 LAST VOLTAGE 16V
J 0
(3525 975);
DISPLAY 0.617021 (3525 975);
PAINT SKYBLUE (3525 975);
FORCEPROP 1 LAST PACK_TYPE 0402V
J 0
(3525 775);
DISPLAY 0.617021 (3525 775);
PAINT SKYBLUE (3525 775);
FORCEPROP 1 LAST TOLERANCE 10%
J 0
(3525 925);
DISPLAY 0.617021 (3525 925);
PAINT SKYBLUE (3525 925);
FORCEPROP 1 LAST PART_NUMBER A36096-030
J 0
(3525 825);
DISPLAY 0.617021 (3525 825);
PAINT BLUE (3525 825);
FORCEPROP 1 LASTPIN (3475 1075) $PN 1
J 0
(3485 1055);
DISPLAY 0.617021 (3485 1055);
PAINT ORANGE (3485 1055);
FORCEPROP 1 LAST VALUE 0.1UF
J 0
(3525 1025);
DISPLAY 0.617021 (3525 1025);
PAINT SKYBLUE (3525 1025);
FORCEPROP 1 LAST LOCATION C6P12
J 0
(3525 1075);
DISPLAY 0.617021 (3525 1075);
PAINT AQUA (3525 1075);
FORCEPROP 2 LAST CDS_LIB dev_discrete
J 0
(3475 975);
PAINT ORANGE (3475 975);
DISPLAY INVISIBLE (3475 975);
FORCEPROP 2 LAST CDS_LOCATION C6P12
J 0
(3525 1075);
DISPLAY 0.617021 (3525 1075);
PAINT AQUA (3525 1075);
DISPLAY INVISIBLE (3525 1075);
FORCEPROP 1 LAST PATH I15
J 0
(3525 1125);
DISPLAY 0.978723 (3525 1125);
PAINT WHITE (3525 1125);
DISPLAY INVISIBLE (3525 1125);
FORCEPROP 2 LAST CDS_SEC 1
J 0
(3525 1125);
PAINT ORANGE (3525 1125);
DISPLAY INVISIBLE (3525 1125);
FORCEPROP 2 LAST ROOM DB1200ZL
J 0
(3525 1175);
DISPLAY 1.021277 (3525 1175);
PAINT ORANGE (3525 1175);
DISPLAY INVISIBLE (3525 1175);
FORCEPROP 2 LAST SEC_TYPE 0402V
J 0
(3525 1175);
DISPLAY 1.021277 (3525 1175);
PAINT ORANGE (3525 1175);
DISPLAY INVISIBLE (3525 1175);
FORCEPROP 2 LAST SEC 1
J 0
(3525 1175);
DISPLAY 0.680851 (3525 1175);
PAINT MONO (3525 1175);
DISPLAY INVISIBLE (3525 1175);
FORCEPROP 2 LAST BOM_COST SYS_CLOCK
J 0
(3525 1275);
DISPLAY 1.021277 (3525 1275);
PAINT ORANGE (3525 1275);
DISPLAY INVISIBLE (3525 1275);
FORCEADD CAP_A..1
(3700 975);
FORCEPROP 1 LASTPIN (3700 875) $PN 2
J 0
(3710 855);
DISPLAY 0.617021 (3710 855);
PAINT ORANGE (3710 855);
FORCEPROP 1 LAST MATERIAL X7R
J 0
(3750 875);
DISPLAY 0.617021 (3750 875);
PAINT SKYBLUE (3750 875);
FORCEPROP 1 LAST VOLTAGE 16V
J 0
(3750 975);
DISPLAY 0.617021 (3750 975);
PAINT SKYBLUE (3750 975);
FORCEPROP 1 LAST TOLERANCE 10%
J 0
(3750 925);
DISPLAY 0.617021 (3750 925);
PAINT SKYBLUE (3750 925);
FORCEPROP 1 LAST PACK_TYPE 0402V
J 0
(3750 775);
DISPLAY 0.617021 (3750 775);
PAINT SKYBLUE (3750 775);
FORCEPROP 1 LAST PART_NUMBER A36096-030
J 0
(3750 825);
DISPLAY 0.617021 (3750 825);
PAINT BLUE (3750 825);
FORCEPROP 1 LASTPIN (3700 1075) $PN 1
J 0
(3710 1055);
DISPLAY 0.617021 (3710 1055);
PAINT ORANGE (3710 1055);
FORCEPROP 1 LAST VALUE 0.1UF
J 0
(3750 1025);
DISPLAY 0.617021 (3750 1025);
PAINT SKYBLUE (3750 1025);
FORCEPROP 1 LAST LOCATION C6P11
J 0
(3750 1075);
DISPLAY 0.617021 (3750 1075);
PAINT AQUA (3750 1075);
FORCEPROP 2 LAST CDS_LIB dev_discrete
J 0
(3700 975);
PAINT ORANGE (3700 975);
DISPLAY INVISIBLE (3700 975);
FORCEPROP 1 LAST PATH I16
J 0
(3750 1125);
DISPLAY 0.978723 (3750 1125);
PAINT WHITE (3750 1125);
DISPLAY INVISIBLE (3750 1125);
FORCEPROP 2 LAST ROOM DB1200ZL
J 0
(3750 1175);
DISPLAY 1.021277 (3750 1175);
PAINT ORANGE (3750 1175);
DISPLAY INVISIBLE (3750 1175);
FORCEPROP 2 LAST CDS_LOCATION C6P11
J 0
(3750 1075);
DISPLAY 0.617021 (3750 1075);
PAINT AQUA (3750 1075);
DISPLAY INVISIBLE (3750 1075);
FORCEPROP 2 LAST SEC 1
J 0
(3750 1175);
DISPLAY 0.680851 (3750 1175);
PAINT MONO (3750 1175);
DISPLAY INVISIBLE (3750 1175);
FORCEPROP 2 LAST SEC_TYPE 0402V
J 0
(3750 1175);
DISPLAY 1.021277 (3750 1175);
PAINT ORANGE (3750 1175);
DISPLAY INVISIBLE (3750 1175);
FORCEPROP 2 LAST CDS_SEC 1
J 0
(3750 1125);
PAINT ORANGE (3750 1125);
DISPLAY INVISIBLE (3750 1125);
FORCEPROP 2 LAST BOM_COST SYS_CLOCK
J 0
(3750 1275);
DISPLAY 1.021277 (3750 1275);
PAINT ORANGE (3750 1275);
DISPLAY INVISIBLE (3750 1275);
FORCEADD GND..1
(3700 625);
FORCEPROP 3 LASTPIN (3700 675) SIG_NAME GND\g
J 0
(3710 685);
DISPLAY 0.659574 (3710 685);
PAINT MONO (3710 685);
DISPLAY INVISIBLE (3710 685);
FORCEPROP 2 LAST BOM_COST SYS_CLOCK
J 0
(3250 700);
DISPLAY 1.617021 (3250 700);
PAINT WHITE (3250 700);
DISPLAY INVISIBLE (3250 700);
FORCEPROP 2 LAST ROOM DB1200ZL
J 0
(3375 700);
DISPLAY 1.127660 (3375 700);
PAINT WHITE (3375 700);
DISPLAY INVISIBLE (3375 700);
FORCEPROP 1 LAST BODY_TYPE PLUMBING
J 0
(3655 582);
DISPLAY 0.340426 (3655 582);
PAINT GREEN (3655 582);
DISPLAY INVISIBLE (3655 582);
FORCEPROP 2 LAST CDS_LIB mstr_symbols
J 0
(3700 625);
PAINT ORANGE (3700 625);
DISPLAY INVISIBLE (3700 625);
FORCEPROP 1 LAST VOLTAGE 0.0V
J 0
(3655 582);
DISPLAY 0.340426 (3655 582);
PAINT SKYBLUE (3655 582);
DISPLAY INVISIBLE (3655 582);
FORCEPROP 1 LAST SIZE 1B
J 0
(3775 575);
DISPLAY 1.127660 (3775 575);
PAINT ORANGE (3775 575);
DISPLAY INVISIBLE (3775 575);
FORCEPROP 1 LAST PATH I17
J 0
(3775 625);
DISPLAY 0.872340 (3775 625);
PAINT AQUA (3775 625);
DISPLAY INVISIBLE (3775 625);
FORCEPROP 1 LAST HDL_POWER GND
J 0
(3700 775);
PAINT GREEN (3700 775);
DISPLAY INVISIBLE (3700 775);
FORCEADD CAP_A..1
(-1550 3975);
FORCEPROP 1 LASTPIN (-1550 3875) $PN 2
J 0
(-1540 3855);
DISPLAY 0.617021 (-1540 3855);
PAINT ORANGE (-1540 3855);
FORCEPROP 1 LASTPIN (-1550 4075) $PN 1
J 0
(-1540 4055);
DISPLAY 0.617021 (-1540 4055);
PAINT ORANGE (-1540 4055);
FORCEPROP 1 LAST MATERIAL X7R
J 0
(-1500 3875);
DISPLAY 0.617021 (-1500 3875);
PAINT SKYBLUE (-1500 3875);
FORCEPROP 1 LAST VOLTAGE 16V
J 0
(-1500 3975);
DISPLAY 0.617021 (-1500 3975);
PAINT SKYBLUE (-1500 3975);
FORCEPROP 1 LAST PACK_TYPE 0402V
J 0
(-1500 3775);
DISPLAY 0.617021 (-1500 3775);
PAINT SKYBLUE (-1500 3775);
FORCEPROP 1 LAST TOLERANCE 10%
J 0
(-1500 3925);
DISPLAY 0.617021 (-1500 3925);
PAINT SKYBLUE (-1500 3925);
FORCEPROP 1 LAST VALUE 0.1UF
J 0
(-1500 4025);
DISPLAY 0.617021 (-1500 4025);
PAINT SKYBLUE (-1500 4025);
FORCEPROP 1 LAST PART_NUMBER A36096-030
J 0
(-1500 3825);
DISPLAY 0.617021 (-1500 3825);
PAINT BLUE (-1500 3825);
FORCEPROP 1 LAST LOCATION C4D24
J 0
(-1500 4075);
DISPLAY 0.617021 (-1500 4075);
PAINT AQUA (-1500 4075);
FORCEPROP 2 LAST CDS_LIB dev_discrete
J 0
(-1550 3975);
PAINT ORANGE (-1550 3975);
DISPLAY INVISIBLE (-1550 3975);
FORCEPROP 2 LAST CDS_LOCATION C4D24
J 0
(-1500 4075);
DISPLAY 0.617021 (-1500 4075);
PAINT AQUA (-1500 4075);
DISPLAY INVISIBLE (-1500 4075);
FORCEPROP 2 LAST SEC 1
J 0
(-1500 4175);
DISPLAY 0.680851 (-1500 4175);
PAINT MONO (-1500 4175);
DISPLAY INVISIBLE (-1500 4175);
FORCEPROP 2 LAST SEC_TYPE 0402V
J 0
(-1500 4175);
DISPLAY 1.021277 (-1500 4175);
PAINT ORANGE (-1500 4175);
DISPLAY INVISIBLE (-1500 4175);
FORCEPROP 2 LAST CDS_SEC 1
J 0
(-1500 4125);
PAINT ORANGE (-1500 4125);
DISPLAY INVISIBLE (-1500 4125);
FORCEPROP 2 LAST BOM_COST SYS_CLOCK
J 0
(-1500 4275);
DISPLAY 1.021277 (-1500 4275);
PAINT ORANGE (-1500 4275);
DISPLAY INVISIBLE (-1500 4275);
FORCEPROP 2 LAST ROOM DB1200ZL
J 0
(-1500 4175);
DISPLAY 1.021277 (-1500 4175);
PAINT ORANGE (-1500 4175);
DISPLAY INVISIBLE (-1500 4175);
FORCEPROP 1 LAST PATH I18
J 0
(-1500 4125);
DISPLAY 0.978723 (-1500 4125);
PAINT WHITE (-1500 4125);
DISPLAY INVISIBLE (-1500 4125);
FORCEADD CAP_A..1
(-1800 3975);
FORCEPROP 1 LAST PACK_TYPE 0402V
J 0
(-1750 3775);
DISPLAY 0.617021 (-1750 3775);
PAINT SKYBLUE (-1750 3775);
FORCEPROP 1 LAST MATERIAL X6S
J 0
(-1750 3875);
DISPLAY 0.617021 (-1750 3875);
PAINT SKYBLUE (-1750 3875);
FORCEPROP 1 LASTPIN (-1800 3875) $PN 2
J 0
(-1790 3855);
DISPLAY 0.617021 (-1790 3855);
PAINT ORANGE (-1790 3855);
FORCEPROP 1 LASTPIN (-1800 4075) $PN 1
J 0
(-1790 4055);
DISPLAY 0.617021 (-1790 4055);
PAINT ORANGE (-1790 4055);
FORCEPROP 1 LAST TOLERANCE 10%
J 0
(-1750 3925);
DISPLAY 0.617021 (-1750 3925);
PAINT SKYBLUE (-1750 3925);
FORCEPROP 1 LAST VOLTAGE 6.3V
J 0
(-1750 3975);
DISPLAY 0.617021 (-1750 3975);
PAINT SKYBLUE (-1750 3975);
FORCEPROP 1 LAST VALUE 1.0UF
J 0
(-1750 4025);
DISPLAY 0.617021 (-1750 4025);
PAINT SKYBLUE (-1750 4025);
FORCEPROP 1 LAST PART_NUMBER D97712-004
J 0
(-1750 3825);
DISPLAY 0.617021 (-1750 3825);
PAINT BLUE (-1750 3825);
FORCEPROP 1 LAST LOCATION C4D23
J 0
(-1750 4075);
DISPLAY 0.617021 (-1750 4075);
PAINT AQUA (-1750 4075);
FORCEPROP 2 LAST CDS_LIB dev_discrete
J 0
(-1800 3975);
PAINT ORANGE (-1800 3975);
DISPLAY INVISIBLE (-1800 3975);
FORCEPROP 2 LAST CDS_LOCATION C4D23
J 0
(-1750 4075);
DISPLAY 0.617021 (-1750 4075);
PAINT AQUA (-1750 4075);
DISPLAY INVISIBLE (-1750 4075);
FORCEPROP 2 LAST ROOM DB1200ZL
J 0
(-1750 4175);
DISPLAY 1.021277 (-1750 4175);
PAINT ORANGE (-1750 4175);
DISPLAY INVISIBLE (-1750 4175);
FORCEPROP 1 LAST PATH I19
J 0
(-1750 4125);
DISPLAY 0.978723 (-1750 4125);
PAINT WHITE (-1750 4125);
DISPLAY INVISIBLE (-1750 4125);
FORCEPROP 2 LAST SEC 1
J 0
(-1750 4175);
DISPLAY 0.680851 (-1750 4175);
PAINT MONO (-1750 4175);
DISPLAY INVISIBLE (-1750 4175);
FORCEPROP 2 LAST SEC_TYPE 0402V
J 0
(-1750 4175);
DISPLAY 1.021277 (-1750 4175);
PAINT ORANGE (-1750 4175);
DISPLAY INVISIBLE (-1750 4175);
FORCEPROP 2 LAST CDS_SEC 1
J 0
(-1750 4125);
PAINT ORANGE (-1750 4125);
DISPLAY INVISIBLE (-1750 4125);
FORCEPROP 2 LAST BOM_COST SYS_CLOCK
J 0
(-1750 4275);
DISPLAY 1.021277 (-1750 4275);
PAINT ORANGE (-1750 4275);
DISPLAY INVISIBLE (-1750 4275);
FORCEADD RES..1
(-2425 4200);
FORCEPROP 1 LAST WATTAGE 1/10W
J 2
(-2450 4050);
DISPLAY 0.617021 (-2450 4050);
PAINT SKYBLUE (-2450 4050);
FORCEPROP 1 LAST MATERIAL CHIP
J 0
(-2425 4050);
DISPLAY 0.617021 (-2425 4050);
PAINT SKYBLUE (-2425 4050);
FORCEPROP 1 LAST PACK_TYPE 0603
J 0
(-2550 4000);
DISPLAY 0.617021 (-2550 4000);
PAINT SKYBLUE (-2550 4000);
FORCEPROP 1 LAST VALUE 2.2
J 2
(-2450 4100);
DISPLAY 0.617021 (-2450 4100);
PAINT SKYBLUE (-2450 4100);
FORCEPROP 1 LASTPIN (-2525 4200) $PN 1
J 0
(-2513 4212);
DISPLAY 0.617021 (-2513 4212);
PAINT ORANGE (-2513 4212);
FORCEPROP 1 LAST LOCATION R3D14
J 0
(-2475 4250);
DISPLAY 0.617021 (-2475 4250);
PAINT AQUA (-2475 4250);
FORCEPROP 1 LAST TOLERANCE 1.0%
J 0
(-2425 4100);
DISPLAY 0.617021 (-2425 4100);
PAINT SKYBLUE (-2425 4100);
FORCEPROP 1 LASTPIN (-2325 4200) $PN 2
J 0
(-2363 4212);
DISPLAY 0.617021 (-2363 4212);
PAINT ORANGE (-2363 4212);
FORCEPROP 1 LAST PART_NUMBER G22026-127
J 0
(-2475 4300);
DISPLAY 0.617021 (-2475 4300);
PAINT BLUE (-2475 4300);
FORCEPROP 2 LAST CDS_LOCATION R3D14
J 0
(-2475 4250);
DISPLAY 0.617021 (-2475 4250);
PAINT AQUA (-2475 4250);
DISPLAY INVISIBLE (-2475 4250);
FORCEPROP 2 LAST CDS_LIB mstr_discrete
J 0
(-2425 4200);
PAINT ORANGE (-2425 4200);
DISPLAY INVISIBLE (-2425 4200);
FORCEPROP 1 LAST PATH I21
J 0
(-2475 4350);
DISPLAY 0.978723 (-2475 4350);
PAINT WHITE (-2475 4350);
DISPLAY INVISIBLE (-2475 4350);
FORCEPROP 2 LAST ROOM DB1200ZL
J 0
(-2475 4400);
DISPLAY 1.021277 (-2475 4400);
PAINT ORANGE (-2475 4400);
DISPLAY INVISIBLE (-2475 4400);
FORCEPROP 2 LAST SEC 1
J 0
(-2475 4400);
DISPLAY 0.680851 (-2475 4400);
PAINT MONO (-2475 4400);
DISPLAY INVISIBLE (-2475 4400);
FORCEPROP 2 LAST SEC_TYPE 0603
J 0
(-2475 4400);
DISPLAY 1.021277 (-2475 4400);
PAINT ORANGE (-2475 4400);
DISPLAY INVISIBLE (-2475 4400);
FORCEPROP 2 LAST BOM_COST SYS_CLOCK
J 0
(-2475 4500);
DISPLAY 1.021277 (-2475 4500);
PAINT ORANGE (-2475 4500);
DISPLAY INVISIBLE (-2475 4500);
FORCEADD GND..1
(-1550 3625);
FORCEPROP 3 LASTPIN (-1550 3675) SIG_NAME GND\g
J 0
(-1540 3685);
DISPLAY 0.659574 (-1540 3685);
PAINT MONO (-1540 3685);
DISPLAY INVISIBLE (-1540 3685);
FORCEPROP 1 LAST BODY_TYPE PLUMBING
J 0
(-1595 3582);
DISPLAY 0.340426 (-1595 3582);
PAINT GREEN (-1595 3582);
DISPLAY INVISIBLE (-1595 3582);
FORCEPROP 1 LAST VOLTAGE 0.0V
J 0
(-1595 3582);
DISPLAY 0.340426 (-1595 3582);
PAINT SKYBLUE (-1595 3582);
DISPLAY INVISIBLE (-1595 3582);
FORCEPROP 2 LAST ROOM DB1200ZL
J 0
(-1875 3700);
DISPLAY 1.127660 (-1875 3700);
PAINT WHITE (-1875 3700);
DISPLAY INVISIBLE (-1875 3700);
FORCEPROP 2 LAST BOM_COST SYS_CLOCK
J 0
(-2000 3700);
DISPLAY 1.617021 (-2000 3700);
PAINT WHITE (-2000 3700);
DISPLAY INVISIBLE (-2000 3700);
FORCEPROP 1 LAST HDL_POWER GND
J 0
(-1550 3775);
PAINT GREEN (-1550 3775);
DISPLAY INVISIBLE (-1550 3775);
FORCEPROP 2 LAST CDS_LIB mstr_symbols
J 0
(-1550 3625);
PAINT ORANGE (-1550 3625);
DISPLAY INVISIBLE (-1550 3625);
FORCEPROP 1 LAST SIZE 1B
J 0
(-1475 3575);
DISPLAY 1.127660 (-1475 3575);
PAINT ORANGE (-1475 3575);
DISPLAY INVISIBLE (-1475 3575);
FORCEPROP 1 LAST PATH I22
J 0
(-1475 3625);
DISPLAY 0.872340 (-1475 3625);
PAINT AQUA (-1475 3625);
DISPLAY INVISIBLE (-1475 3625);
FORCEADD VCC_CORE..1
(3700 1375);
FORCEPROP 3 LASTPIN (3700 1325) SIG_NAME P3V3_DB1200\g
J 0
(3710 1335);
DISPLAY 0.659574 (3710 1335);
PAINT MONO (3710 1335);
DISPLAY INVISIBLE (3710 1335);
FORCEPROP 1 LAST HDL_POWER P3V3_DB1200
J 1
(3750 1425);
DISPLAY 0.617021 (3750 1425);
PAINT GREEN (3750 1425);
FORCEPROP 0 LAST VOLTAGE 5
J 0
(3700 1375);
PAINT SKYBLUE (3700 1375);
DISPLAY INVISIBLE (3700 1375);
FORCEPROP 2 LAST CDS_LIB mstr_symbols
J 0
(3700 1375);
PAINT ORANGE (3700 1375);
DISPLAY INVISIBLE (3700 1375);
FORCEPROP 1 LAST PATH I23
J 0
(3750 1400);
DISPLAY 0.872340 (3750 1400);
PAINT AQUA (3750 1400);
DISPLAY INVISIBLE (3750 1400);
FORCEADD VCC_CORE..1
(-2800 4325);
FORCEPROP 3 LASTPIN (-2800 4275) SIG_NAME P3V3_DB1200\g
J 0
(-2790 4285);
DISPLAY 0.659574 (-2790 4285);
PAINT MONO (-2790 4285);
DISPLAY INVISIBLE (-2790 4285);
FORCEPROP 1 LAST HDL_POWER P3V3_DB1200
J 1
(-2750 4375);
DISPLAY 0.617021 (-2750 4375);
PAINT GREEN (-2750 4375);
FORCEPROP 0 LAST VOLTAGE 5
J 0
(-2800 4325);
PAINT SKYBLUE (-2800 4325);
DISPLAY INVISIBLE (-2800 4325);
FORCEPROP 2 LAST CDS_LIB mstr_symbols
J 0
(-2800 4325);
PAINT ORANGE (-2800 4325);
DISPLAY INVISIBLE (-2800 4325);
FORCEPROP 1 LAST PATH I24
J 0
(-2750 4350);
DISPLAY 0.872340 (-2750 4350);
PAINT AQUA (-2750 4350);
DISPLAY INVISIBLE (-2750 4350);
FORCEADD VCC_CORE..1
(-825 4000);
FORCEPROP 3 LASTPIN (-825 3950) SIG_NAME P3V3_DB1200\g
J 0
(-815 3960);
DISPLAY 0.659574 (-815 3960);
PAINT MONO (-815 3960);
DISPLAY INVISIBLE (-815 3960);
FORCEPROP 1 LAST HDL_POWER P3V3_DB1200
J 1
(-775 4050);
DISPLAY 0.617021 (-775 4050);
PAINT GREEN (-775 4050);
FORCEPROP 1 LAST PATH I25
J 0
(-775 4025);
DISPLAY 0.872340 (-775 4025);
PAINT AQUA (-775 4025);
DISPLAY INVISIBLE (-775 4025);
FORCEPROP 2 LAST CDS_LIB mstr_symbols
J 0
(-825 4000);
PAINT ORANGE (-825 4000);
DISPLAY INVISIBLE (-825 4000);
FORCEPROP 0 LAST VOLTAGE 5
J 0
(-825 4000);
PAINT SKYBLUE (-825 4000);
DISPLAY INVISIBLE (-825 4000);
FORCEADD RES..1
(-2825 3475);
FORCEPROP 1 LASTPIN (-2925 3475) $PN 1
J 0
(-2913 3487);
DISPLAY 0.617021 (-2913 3487);
PAINT ORANGE (-2913 3487);
FORCEPROP 1 LAST WATTAGE 1/10W
J 2
(-2850 3325);
DISPLAY 0.617021 (-2850 3325);
PAINT SKYBLUE (-2850 3325);
FORCEPROP 1 LAST PACK_TYPE 0603
J 0
(-2950 3275);
DISPLAY 0.617021 (-2950 3275);
PAINT SKYBLUE (-2950 3275);
FORCEPROP 1 LAST VALUE 2.2
J 2
(-2850 3375);
DISPLAY 0.617021 (-2850 3375);
PAINT SKYBLUE (-2850 3375);
FORCEPROP 1 LAST MATERIAL CHIP
J 0
(-2825 3325);
DISPLAY 0.617021 (-2825 3325);
PAINT SKYBLUE (-2825 3325);
FORCEPROP 1 LAST TOLERANCE 1.0%
J 0
(-2825 3375);
DISPLAY 0.617021 (-2825 3375);
PAINT SKYBLUE (-2825 3375);
FORCEPROP 1 LAST LOCATION R6P25
J 0
(-2875 3525);
DISPLAY 0.617021 (-2875 3525);
PAINT AQUA (-2875 3525);
FORCEPROP 1 LASTPIN (-2725 3475) $PN 2
J 0
(-2763 3487);
DISPLAY 0.617021 (-2763 3487);
PAINT ORANGE (-2763 3487);
FORCEPROP 1 LAST PART_NUMBER G22026-127
J 0
(-2875 3575);
DISPLAY 0.617021 (-2875 3575);
PAINT BLUE (-2875 3575);
FORCEPROP 2 LAST CDS_LOCATION R6P25
J 0
(-2875 3525);
DISPLAY 0.617021 (-2875 3525);
PAINT AQUA (-2875 3525);
DISPLAY INVISIBLE (-2875 3525);
FORCEPROP 2 LAST CDS_LIB mstr_discrete
J 0
(-2825 3475);
PAINT ORANGE (-2825 3475);
DISPLAY INVISIBLE (-2825 3475);
FORCEPROP 2 LAST ROOM DB1200ZL
J 0
(-2875 3675);
DISPLAY 1.021277 (-2875 3675);
PAINT ORANGE (-2875 3675);
DISPLAY INVISIBLE (-2875 3675);
FORCEPROP 1 LAST PATH I26
J 0
(-2875 3625);
DISPLAY 0.978723 (-2875 3625);
PAINT WHITE (-2875 3625);
DISPLAY INVISIBLE (-2875 3625);
FORCEPROP 2 LAST SEC 1
J 0
(-2875 3675);
DISPLAY 0.680851 (-2875 3675);
PAINT MONO (-2875 3675);
DISPLAY INVISIBLE (-2875 3675);
FORCEPROP 2 LAST SEC_TYPE 0603
J 0
(-2875 3675);
DISPLAY 1.021277 (-2875 3675);
PAINT ORANGE (-2875 3675);
DISPLAY INVISIBLE (-2875 3675);
FORCEPROP 2 LAST BOM_COST SYS_CLOCK
J 0
(-2875 3775);
DISPLAY 1.021277 (-2875 3775);
PAINT ORANGE (-2875 3775);
DISPLAY INVISIBLE (-2875 3775);
FORCEADD VCC_CORE..1
(-3125 3625);
FORCEPROP 3 LASTPIN (-3125 3575) SIG_NAME P3V3_DB1200\g
J 0
(-3115 3585);
DISPLAY 0.659574 (-3115 3585);
PAINT MONO (-3115 3585);
DISPLAY INVISIBLE (-3115 3585);
FORCEPROP 1 LAST HDL_POWER P3V3_DB1200
J 1
(-3075 3675);
DISPLAY 0.617021 (-3075 3675);
PAINT GREEN (-3075 3675);
FORCEPROP 1 LAST PATH I27
J 0
(-3075 3650);
DISPLAY 0.872340 (-3075 3650);
PAINT AQUA (-3075 3650);
DISPLAY INVISIBLE (-3075 3650);
FORCEPROP 2 LAST CDS_LIB mstr_symbols
J 0
(-3125 3625);
PAINT ORANGE (-3125 3625);
DISPLAY INVISIBLE (-3125 3625);
FORCEPROP 0 LAST VOLTAGE 5
J 0
(-3125 3625);
PAINT SKYBLUE (-3125 3625);
DISPLAY INVISIBLE (-3125 3625);
FORCEADD CAP_A..1
(-2325 3300);
FORCEPROP 1 LASTPIN (-2325 3200) $PN 2
J 0
(-2315 3180);
DISPLAY 0.617021 (-2315 3180);
PAINT ORANGE (-2315 3180);
FORCEPROP 1 LASTPIN (-2325 3400) $PN 1
J 0
(-2315 3380);
DISPLAY 0.617021 (-2315 3380);
PAINT ORANGE (-2315 3380);
FORCEPROP 1 LAST MATERIAL X7R
J 0
(-2275 3200);
DISPLAY 0.617021 (-2275 3200);
PAINT SKYBLUE (-2275 3200);
FORCEPROP 1 LAST VOLTAGE 16V
J 0
(-2275 3300);
DISPLAY 0.617021 (-2275 3300);
PAINT SKYBLUE (-2275 3300);
FORCEPROP 1 LAST PACK_TYPE 0402V
J 0
(-2275 3100);
DISPLAY 0.617021 (-2275 3100);
PAINT SKYBLUE (-2275 3100);
FORCEPROP 1 LAST TOLERANCE 10%
J 0
(-2275 3250);
DISPLAY 0.617021 (-2275 3250);
PAINT SKYBLUE (-2275 3250);
FORCEPROP 1 LAST VALUE 0.1UF
J 0
(-2275 3350);
DISPLAY 0.617021 (-2275 3350);
PAINT SKYBLUE (-2275 3350);
FORCEPROP 1 LAST LOCATION C4D22
J 0
(-2275 3400);
DISPLAY 0.617021 (-2275 3400);
PAINT AQUA (-2275 3400);
FORCEPROP 1 LAST PART_NUMBER A36096-030
J 0
(-2275 3150);
DISPLAY 0.617021 (-2275 3150);
PAINT BLUE (-2275 3150);
FORCEPROP 2 LAST CDS_LIB dev_discrete
J 0
(-2325 3300);
PAINT ORANGE (-2325 3300);
DISPLAY INVISIBLE (-2325 3300);
FORCEPROP 2 LAST SEC 1
J 0
(-2275 3500);
DISPLAY 0.680851 (-2275 3500);
PAINT MONO (-2275 3500);
DISPLAY INVISIBLE (-2275 3500);
FORCEPROP 2 LAST SEC_TYPE 0402V
J 0
(-2275 3500);
DISPLAY 1.021277 (-2275 3500);
PAINT ORANGE (-2275 3500);
DISPLAY INVISIBLE (-2275 3500);
FORCEPROP 2 LAST CDS_SEC 1
J 0
(-2275 3450);
PAINT ORANGE (-2275 3450);
DISPLAY INVISIBLE (-2275 3450);
FORCEPROP 2 LAST CDS_LOCATION C4D22
J 0
(-2275 3400);
DISPLAY 0.617021 (-2275 3400);
PAINT AQUA (-2275 3400);
DISPLAY INVISIBLE (-2275 3400);
FORCEPROP 2 LAST ROOM DB1200ZL
J 0
(-2275 3500);
DISPLAY 1.021277 (-2275 3500);
PAINT ORANGE (-2275 3500);
DISPLAY INVISIBLE (-2275 3500);
FORCEPROP 1 LAST PATH I28
J 0
(-2275 3450);
DISPLAY 0.978723 (-2275 3450);
PAINT WHITE (-2275 3450);
DISPLAY INVISIBLE (-2275 3450);
FORCEPROP 2 LAST BOM_COST SYS_CLOCK
J 0
(-2275 3600);
DISPLAY 1.021277 (-2275 3600);
PAINT ORANGE (-2275 3600);
DISPLAY INVISIBLE (-2275 3600);
FORCEADD GND..1
(-2325 2975);
FORCEPROP 3 LASTPIN (-2325 3025) SIG_NAME GND\g
J 0
(-2315 3035);
DISPLAY 0.659574 (-2315 3035);
PAINT MONO (-2315 3035);
DISPLAY INVISIBLE (-2315 3035);
FORCEPROP 1 LAST PATH I29
J 0
(-2250 2975);
DISPLAY 0.872340 (-2250 2975);
PAINT AQUA (-2250 2975);
DISPLAY INVISIBLE (-2250 2975);
FORCEPROP 1 LAST BODY_TYPE PLUMBING
J 0
(-2370 2932);
DISPLAY 0.340426 (-2370 2932);
PAINT GREEN (-2370 2932);
DISPLAY INVISIBLE (-2370 2932);
FORCEPROP 1 LAST SIZE 1B
J 0
(-2250 2925);
DISPLAY 1.127660 (-2250 2925);
PAINT ORANGE (-2250 2925);
DISPLAY INVISIBLE (-2250 2925);
FORCEPROP 2 LAST CDS_LIB mstr_symbols
J 0
(-2325 2975);
PAINT ORANGE (-2325 2975);
DISPLAY INVISIBLE (-2325 2975);
FORCEPROP 1 LAST VOLTAGE 0.0V
J 0
(-2370 2932);
DISPLAY 0.340426 (-2370 2932);
PAINT SKYBLUE (-2370 2932);
DISPLAY INVISIBLE (-2370 2932);
FORCEPROP 2 LAST ROOM DB1200ZL
J 0
(-2650 3050);
DISPLAY 1.127660 (-2650 3050);
PAINT WHITE (-2650 3050);
DISPLAY INVISIBLE (-2650 3050);
FORCEPROP 2 LAST BOM_COST SYS_CLOCK
J 0
(-2775 3050);
DISPLAY 1.617021 (-2775 3050);
PAINT WHITE (-2775 3050);
DISPLAY INVISIBLE (-2775 3050);
FORCEPROP 1 LAST HDL_POWER GND
J 0
(-2325 3125);
PAINT GREEN (-2325 3125);
DISPLAY INVISIBLE (-2325 3125);
FORCEADD CAP_A..1
(-2575 3300);
FORCEPROP 1 LASTPIN (-2575 3200) $PN 2
J 0
(-2565 3180);
DISPLAY 0.617021 (-2565 3180);
PAINT ORANGE (-2565 3180);
FORCEPROP 1 LASTPIN (-2575 3400) $PN 1
J 0
(-2565 3380);
DISPLAY 0.617021 (-2565 3380);
PAINT ORANGE (-2565 3380);
FORCEPROP 1 LAST MATERIAL X6S
J 0
(-2525 3200);
DISPLAY 0.617021 (-2525 3200);
PAINT SKYBLUE (-2525 3200);
FORCEPROP 1 LAST VOLTAGE 6.3V
J 0
(-2525 3300);
DISPLAY 0.617021 (-2525 3300);
PAINT SKYBLUE (-2525 3300);
FORCEPROP 1 LAST PACK_TYPE 0402V
J 0
(-2525 3100);
DISPLAY 0.617021 (-2525 3100);
PAINT SKYBLUE (-2525 3100);
FORCEPROP 1 LAST TOLERANCE 10%
J 0
(-2525 3250);
DISPLAY 0.617021 (-2525 3250);
PAINT SKYBLUE (-2525 3250);
FORCEPROP 1 LAST VALUE 1.0UF
J 0
(-2525 3350);
DISPLAY 0.617021 (-2525 3350);
PAINT SKYBLUE (-2525 3350);
FORCEPROP 1 LAST LOCATION C4D27
J 0
(-2525 3400);
DISPLAY 0.617021 (-2525 3400);
PAINT AQUA (-2525 3400);
FORCEPROP 1 LAST PART_NUMBER D97712-004
J 0
(-2525 3150);
DISPLAY 0.617021 (-2525 3150);
PAINT BLUE (-2525 3150);
FORCEPROP 2 LAST CDS_LIB dev_discrete
J 0
(-2575 3300);
PAINT ORANGE (-2575 3300);
DISPLAY INVISIBLE (-2575 3300);
FORCEPROP 2 LAST ROOM DB1200ZL
J 0
(-2525 3500);
DISPLAY 1.021277 (-2525 3500);
PAINT ORANGE (-2525 3500);
DISPLAY INVISIBLE (-2525 3500);
FORCEPROP 1 LAST PATH I30
J 0
(-2525 3450);
DISPLAY 0.978723 (-2525 3450);
PAINT WHITE (-2525 3450);
DISPLAY INVISIBLE (-2525 3450);
FORCEPROP 2 LAST SEC 1
J 0
(-2525 3500);
DISPLAY 0.680851 (-2525 3500);
PAINT MONO (-2525 3500);
DISPLAY INVISIBLE (-2525 3500);
FORCEPROP 2 LAST SEC_TYPE 0402V
J 0
(-2525 3500);
DISPLAY 1.021277 (-2525 3500);
PAINT ORANGE (-2525 3500);
DISPLAY INVISIBLE (-2525 3500);
FORCEPROP 2 LAST CDS_SEC 1
J 0
(-2525 3450);
PAINT ORANGE (-2525 3450);
DISPLAY INVISIBLE (-2525 3450);
FORCEPROP 2 LAST CDS_LOCATION C4D27
J 0
(-2525 3400);
DISPLAY 0.617021 (-2525 3400);
PAINT AQUA (-2525 3400);
DISPLAY INVISIBLE (-2525 3400);
FORCEPROP 2 LAST BOM_COST SYS_CLOCK
J 0
(-2525 3600);
DISPLAY 1.021277 (-2525 3600);
PAINT ORANGE (-2525 3600);
DISPLAY INVISIBLE (-2525 3600);
FORCEADD OFFPAGE..1
(-1175 3375);
FORCEPROP 2 LAST $XR0 102 
J 0
(-1427 3375);
DISPLAY 0.638298 (-1427 3375);
PAINT MONO (-1427 3375);
FORCEPROP 1 LAST COMMENT_BODY TRUE
J 0
(-1050 3275);
DISPLAY 1.404255 (-1050 3275);
PAINT PEACH (-1050 3275);
DISPLAY INVISIBLE (-1050 3275);
FORCEPROP 2 LAST PATH I31
J 0
(-1125 3450);
DISPLAY 1.021277 (-1125 3450);
PAINT ORANGE (-1125 3450);
DISPLAY INVISIBLE (-1125 3450);
FORCEPROP 2 LAST CDS_LIB mstr_standard
J 0
(-1175 3375);
PAINT ORANGE (-1175 3375);
DISPLAY INVISIBLE (-1175 3375);
FORCEPROP 1 LAST OFFPAGE TRUE
J 0
(-850 3250);
PAINT GREEN (-850 3250);
DISPLAY INVISIBLE (-850 3250);
FORCEADD OFFPAGE..1
(-1175 3325);
FORCEPROP 2 LAST $XR0 102 
J 0
(-1427 3325);
DISPLAY 0.638298 (-1427 3325);
PAINT MONO (-1427 3325);
FORCEPROP 1 LAST COMMENT_BODY TRUE
J 0
(-1050 3225);
DISPLAY 1.404255 (-1050 3225);
PAINT PEACH (-1050 3225);
DISPLAY INVISIBLE (-1050 3225);
FORCEPROP 2 LAST CDS_LIB mstr_standard
J 0
(-1175 3325);
PAINT ORANGE (-1175 3325);
DISPLAY INVISIBLE (-1175 3325);
FORCEPROP 2 LAST PATH I32
J 0
(-1125 3400);
DISPLAY 1.021277 (-1125 3400);
PAINT ORANGE (-1125 3400);
DISPLAY INVISIBLE (-1125 3400);
FORCEPROP 1 LAST OFFPAGE TRUE
J 0
(-850 3200);
PAINT GREEN (-850 3200);
DISPLAY INVISIBLE (-850 3200);
FORCEADD OFFPAGE..1
(-1175 3175);
FORCEPROP 2 LAST $XR0 102 
J 0
(-1457 3175);
DISPLAY 0.638298 (-1457 3175);
PAINT MONO (-1457 3175);
FORCEPROP 2 LAST PATH I33
J 0
(-1425 3225);
DISPLAY 1.021277 (-1425 3225);
PAINT ORANGE (-1425 3225);
DISPLAY INVISIBLE (-1425 3225);
FORCEPROP 2 LAST CDS_LIB mstr_standard
J 0
(-1175 3175);
DISPLAY 1.617021 (-1175 3175);
PAINT MONO (-1175 3175);
DISPLAY INVISIBLE (-1175 3175);
FORCEPROP 1 LAST COMMENT_BODY TRUE
J 0
(-1050 3075);
DISPLAY 1.404255 (-1050 3075);
PAINT PEACH (-1050 3075);
DISPLAY INVISIBLE (-1050 3075);
FORCEPROP 1 LAST OFFPAGE TRUE
J 0
(-850 3050);
PAINT GREEN (-850 3050);
DISPLAY INVISIBLE (-850 3050);
FORCEADD OFFPAGE..3
R 2
(-1175 3225);
FORCEPROP 2 LAST $XR0 102 
J 0
(-1455 3225);
DISPLAY 0.638298 (-1455 3225);
PAINT MONO (-1455 3225);
FORCEPROP 1 LAST OFFPAGE TRUE
J 2
(-1500 3100);
DISPLAY 0.872340 (-1500 3100);
PAINT GREEN (-1500 3100);
DISPLAY INVISIBLE (-1500 3100);
FORCEPROP 2 LAST CDS_LIB mstr_standard
J 2
(-1175 3225);
DISPLAY 1.617021 (-1175 3225);
PAINT MONO (-1175 3225);
DISPLAY INVISIBLE (-1175 3225);
FORCEPROP 1 LAST COMMENT_BODY TRUE
J 2
(-1125 3125);
DISPLAY 0.872340 (-1125 3125);
PAINT GREEN (-1125 3125);
DISPLAY INVISIBLE (-1125 3125);
FORCEPROP 2 LAST PATH I34
J 2
(-925 3275);
DISPLAY 1.021277 (-925 3275);
PAINT ORANGE (-925 3275);
DISPLAY INVISIBLE (-925 3275);
FORCEADD OFFPAGE..1
(-1475 2175);
FORCEPROP 2 LAST $XR0 102 
J 0
(-1727 2175);
DISPLAY 0.638298 (-1727 2175);
PAINT MONO (-1727 2175);
FORCEPROP 2 LAST CDS_LIB mstr_standard
J 0
(-1475 2175);
PAINT ORANGE (-1475 2175);
DISPLAY INVISIBLE (-1475 2175);
FORCEPROP 2 LAST PATH I35
J 0
(-1425 2250);
DISPLAY 1.021277 (-1425 2250);
PAINT ORANGE (-1425 2250);
DISPLAY INVISIBLE (-1425 2250);
FORCEPROP 1 LAST COMMENT_BODY TRUE
J 0
(-1350 2075);
DISPLAY 1.404255 (-1350 2075);
PAINT PEACH (-1350 2075);
DISPLAY INVISIBLE (-1350 2075);
FORCEPROP 1 LAST OFFPAGE TRUE
J 0
(-1150 2050);
PAINT GREEN (-1150 2050);
DISPLAY INVISIBLE (-1150 2050);
FORCEADD OFFPAGE..1
(-1475 2075);
FORCEPROP 2 LAST $XR0 102 
J 0
(-1727 2075);
DISPLAY 0.638298 (-1727 2075);
PAINT MONO (-1727 2075);
FORCEPROP 1 LAST COMMENT_BODY TRUE
J 0
(-1350 1975);
DISPLAY 1.404255 (-1350 1975);
PAINT PEACH (-1350 1975);
DISPLAY INVISIBLE (-1350 1975);
FORCEPROP 1 LAST OFFPAGE TRUE
J 0
(-1150 1950);
PAINT GREEN (-1150 1950);
DISPLAY INVISIBLE (-1150 1950);
FORCEPROP 2 LAST CDS_LIB mstr_standard
J 0
(-1475 2075);
PAINT ORANGE (-1475 2075);
DISPLAY INVISIBLE (-1475 2075);
FORCEPROP 2 LAST PATH I36
J 0
(-1425 2150);
DISPLAY 1.021277 (-1425 2150);
PAINT ORANGE (-1425 2150);
DISPLAY INVISIBLE (-1425 2150);
FORCEADD RES..2
(-2850 2925);
FORCEPROP 1 LASTPIN (-2850 3025) $PN 1
J 0
(-2845 2987);
DISPLAY 0.617021 (-2845 2987);
PAINT ORANGE (-2845 2987);
FORCEPROP 1 LASTPIN (-2850 2825) $PN 2
J 0
(-2845 2835);
DISPLAY 0.617021 (-2845 2835);
PAINT ORANGE (-2845 2835);
FORCEPROP 1 LAST PACK_TYPE 0402
J 0
(-2810 2750);
DISPLAY 0.617021 (-2810 2750);
PAINT SKYBLUE (-2810 2750);
FORCEPROP 1 LAST TOLERANCE 1%
J 0
(-2805 2950);
DISPLAY 0.617021 (-2805 2950);
PAINT SKYBLUE (-2805 2950);
FORCEPROP 1 LAST WATTAGE 1/16W
J 0
(-2810 2900);
DISPLAY 0.617021 (-2810 2900);
PAINT SKYBLUE (-2810 2900);
FORCEPROP 1 LAST VALUE 10.0K
J 0
(-2805 3000);
DISPLAY 0.617021 (-2805 3000);
PAINT SKYBLUE (-2805 3000);
FORCEPROP 1 LAST MATERIAL EMPTY
J 0
(-2810 2850);
DISPLAY 0.617021 (-2810 2850);
PAINT RED (-2810 2850);
FORCEPROP 1 LAST PART_NUMBER G21796-016
J 0
(-2810 2800);
DISPLAY 0.617021 (-2810 2800);
PAINT BLUE (-2810 2800);
FORCEPROP 1 LAST LOCATION R4D38
J 0
(-2805 3050);
DISPLAY 0.617021 (-2805 3050);
PAINT AQUA (-2805 3050);
FORCEPROP 2 LAST CDS_LIB mstr_discrete
J 0
(-2850 2925);
PAINT ORANGE (-2850 2925);
DISPLAY INVISIBLE (-2850 2925);
FORCEPROP 2 LAST CDS_LOCATION R4D38
J 0
(-2805 3050);
DISPLAY 0.617021 (-2805 3050);
PAINT AQUA (-2805 3050);
DISPLAY INVISIBLE (-2805 3050);
FORCEPROP 2 LAST BOM_COST SYS_CLOCK
J 0
(-2800 3250);
DISPLAY 1.021277 (-2800 3250);
PAINT ORANGE (-2800 3250);
DISPLAY INVISIBLE (-2800 3250);
FORCEPROP 2 LAST SEC_TYPE 0402
J 0
(-2800 3150);
DISPLAY 1.021277 (-2800 3150);
PAINT ORANGE (-2800 3150);
DISPLAY INVISIBLE (-2800 3150);
FORCEPROP 2 LAST SEC 1
J 0
(-2800 3150);
DISPLAY 0.680851 (-2800 3150);
PAINT MONO (-2800 3150);
DISPLAY INVISIBLE (-2800 3150);
FORCEPROP 1 LAST PATH I37
J 0
(-2800 3100);
DISPLAY 0.978723 (-2800 3100);
PAINT WHITE (-2800 3100);
DISPLAY INVISIBLE (-2800 3100);
FORCEPROP 2 LAST ROOM DB1200ZL
J 0
(-2800 3150);
DISPLAY 1.021277 (-2800 3150);
PAINT ORANGE (-2800 3150);
DISPLAY INVISIBLE (-2800 3150);
FORCEADD RES..2
(-3225 2925);
FORCEPROP 1 LASTPIN (-3225 3025) $PN 1
J 0
(-3220 2987);
DISPLAY 0.617021 (-3220 2987);
PAINT ORANGE (-3220 2987);
FORCEPROP 1 LASTPIN (-3225 2825) $PN 2
J 0
(-3220 2835);
DISPLAY 0.617021 (-3220 2835);
PAINT ORANGE (-3220 2835);
FORCEPROP 1 LAST TOLERANCE 1%
J 0
(-3180 2950);
DISPLAY 0.617021 (-3180 2950);
PAINT SKYBLUE (-3180 2950);
FORCEPROP 1 LAST WATTAGE 1/16W
J 0
(-3185 2900);
DISPLAY 0.617021 (-3185 2900);
PAINT SKYBLUE (-3185 2900);
FORCEPROP 1 LAST PACK_TYPE 0402
J 0
(-3185 2750);
DISPLAY 0.617021 (-3185 2750);
PAINT SKYBLUE (-3185 2750);
FORCEPROP 1 LAST VALUE 10.0K
J 0
(-3180 3000);
DISPLAY 0.617021 (-3180 3000);
PAINT SKYBLUE (-3180 3000);
FORCEPROP 1 LAST PART_NUMBER G21796-016
J 0
(-3185 2800);
DISPLAY 0.617021 (-3185 2800);
PAINT BLUE (-3185 2800);
FORCEPROP 1 LAST LOCATION R4D35
J 0
(-3180 3050);
DISPLAY 0.617021 (-3180 3050);
PAINT AQUA (-3180 3050);
FORCEPROP 1 LAST MATERIAL EMPTY
J 0
(-3185 2850);
DISPLAY 0.617021 (-3185 2850);
PAINT RED (-3185 2850);
FORCEPROP 2 LAST CDS_LIB mstr_discrete
J 0
(-3225 2925);
PAINT ORANGE (-3225 2925);
DISPLAY INVISIBLE (-3225 2925);
FORCEPROP 2 LAST CDS_LOCATION R4D35
J 0
(-3180 3050);
DISPLAY 0.617021 (-3180 3050);
PAINT AQUA (-3180 3050);
DISPLAY INVISIBLE (-3180 3050);
FORCEPROP 2 LAST BOM_COST SYS_CLOCK
J 0
(-3175 3250);
DISPLAY 1.021277 (-3175 3250);
PAINT ORANGE (-3175 3250);
DISPLAY INVISIBLE (-3175 3250);
FORCEPROP 2 LAST SEC_TYPE 0402
J 0
(-3175 3150);
DISPLAY 1.021277 (-3175 3150);
PAINT ORANGE (-3175 3150);
DISPLAY INVISIBLE (-3175 3150);
FORCEPROP 2 LAST SEC 1
J 0
(-3175 3150);
DISPLAY 0.680851 (-3175 3150);
PAINT MONO (-3175 3150);
DISPLAY INVISIBLE (-3175 3150);
FORCEPROP 1 LAST PATH I38
J 0
(-3175 3100);
DISPLAY 0.978723 (-3175 3100);
PAINT WHITE (-3175 3100);
DISPLAY INVISIBLE (-3175 3100);
FORCEPROP 2 LAST ROOM DB1200ZL
J 0
(-3175 3150);
DISPLAY 1.021277 (-3175 3150);
PAINT ORANGE (-3175 3150);
DISPLAY INVISIBLE (-3175 3150);
FORCEADD OFFPAGE..1
(-1475 2425);
FORCEPROP 2 LAST $XR0 114 
J 0
(-1727 2425);
DISPLAY 0.638298 (-1727 2425);
PAINT MONO (-1727 2425);
FORCEPROP 2 LAST CDS_LIB mstr_standard
J 0
(-1475 2425);
PAINT ORANGE (-1475 2425);
DISPLAY INVISIBLE (-1475 2425);
FORCEPROP 2 LAST PATH I4
J 0
(-1425 2500);
DISPLAY 1.021277 (-1425 2500);
PAINT ORANGE (-1425 2500);
DISPLAY INVISIBLE (-1425 2500);
FORCEPROP 1 LAST COMMENT_BODY TRUE
J 0
(-1350 2325);
DISPLAY 1.404255 (-1350 2325);
PAINT PEACH (-1350 2325);
DISPLAY INVISIBLE (-1350 2325);
FORCEPROP 1 LAST OFFPAGE TRUE
J 0
(-1150 2300);
PAINT GREEN (-1150 2300);
DISPLAY INVISIBLE (-1150 2300);
FORCEADD OFFPAGE..2
(-1950 2775);
FORCEPROP 2 LAST $XR0 102 
J 0
(-1761 2775);
DISPLAY 0.638298 (-1761 2775);
PAINT MONO (-1761 2775);
FORCEPROP 1 LAST COMMENT_BODY TRUE
J 0
(-1995 2680);
DISPLAY 0.872340 (-1995 2680);
PAINT GREEN (-1995 2680);
DISPLAY INVISIBLE (-1995 2680);
FORCEPROP 2 LAST CDS_LIB mstr_standard
J 0
(-1950 2775);
PAINT ORANGE (-1950 2775);
DISPLAY INVISIBLE (-1950 2775);
FORCEPROP 2 LAST PATH I41
J 0
(-1900 2850);
DISPLAY 1.021277 (-1900 2850);
PAINT ORANGE (-1900 2850);
DISPLAY INVISIBLE (-1900 2850);
FORCEPROP 1 LAST OFFPAGE TRUE
J 0
(-1625 2650);
DISPLAY 0.872340 (-1625 2650);
PAINT GREEN (-1625 2650);
DISPLAY INVISIBLE (-1625 2650);
FORCEADD OFFPAGE..2
(-1950 2725);
FORCEPROP 2 LAST $XR0 102 
J 0
(-1761 2725);
DISPLAY 0.638298 (-1761 2725);
PAINT MONO (-1761 2725);
FORCEPROP 1 LAST COMMENT_BODY TRUE
J 0
(-1995 2630);
DISPLAY 0.872340 (-1995 2630);
PAINT GREEN (-1995 2630);
DISPLAY INVISIBLE (-1995 2630);
FORCEPROP 2 LAST CDS_LIB mstr_standard
J 0
(-1950 2725);
PAINT ORANGE (-1950 2725);
DISPLAY INVISIBLE (-1950 2725);
FORCEPROP 2 LAST PATH I42
J 0
(-1775 2800);
DISPLAY 1.021277 (-1775 2800);
PAINT ORANGE (-1775 2800);
DISPLAY INVISIBLE (-1775 2800);
FORCEPROP 1 LAST OFFPAGE TRUE
J 0
(-1625 2600);
DISPLAY 0.872340 (-1625 2600);
PAINT GREEN (-1625 2600);
DISPLAY INVISIBLE (-1625 2600);
FORCEADD VCC_CORE..1
(-3225 3225);
FORCEPROP 3 LASTPIN (-3225 3175) SIG_NAME P3V3_DB1200\g
J 0
(-3215 3185);
DISPLAY 0.659574 (-3215 3185);
PAINT MONO (-3215 3185);
DISPLAY INVISIBLE (-3215 3185);
FORCEPROP 1 LAST HDL_POWER P3V3_DB1200
J 1
(-3175 3275);
DISPLAY 0.617021 (-3175 3275);
PAINT GREEN (-3175 3275);
FORCEPROP 2 LAST CDS_LIB mstr_symbols
J 0
(-3225 3225);
PAINT ORANGE (-3225 3225);
DISPLAY INVISIBLE (-3225 3225);
FORCEPROP 0 LAST VOLTAGE 5
J 0
(-3225 3225);
PAINT SKYBLUE (-3225 3225);
DISPLAY INVISIBLE (-3225 3225);
FORCEPROP 1 LAST PATH I43
J 0
(-3175 3250);
DISPLAY 0.872340 (-3175 3250);
PAINT AQUA (-3175 3250);
DISPLAY INVISIBLE (-3175 3250);
FORCEADD GND..1
(-2850 2200);
FORCEPROP 3 LASTPIN (-2850 2250) SIG_NAME GND\g
J 0
(-2840 2260);
DISPLAY 0.659574 (-2840 2260);
PAINT MONO (-2840 2260);
DISPLAY INVISIBLE (-2840 2260);
FORCEPROP 2 LAST ROOM DB1200ZL
J 0
(-3175 2275);
DISPLAY 1.127660 (-3175 2275);
PAINT WHITE (-3175 2275);
DISPLAY INVISIBLE (-3175 2275);
FORCEPROP 2 LAST BOM_COST SYS_CLOCK
J 0
(-3300 2275);
DISPLAY 1.617021 (-3300 2275);
PAINT WHITE (-3300 2275);
DISPLAY INVISIBLE (-3300 2275);
FORCEPROP 1 LAST BODY_TYPE PLUMBING
J 0
(-2895 2157);
DISPLAY 0.340426 (-2895 2157);
PAINT GREEN (-2895 2157);
DISPLAY INVISIBLE (-2895 2157);
FORCEPROP 1 LAST VOLTAGE 0.0V
J 0
(-2895 2157);
DISPLAY 0.340426 (-2895 2157);
PAINT SKYBLUE (-2895 2157);
DISPLAY INVISIBLE (-2895 2157);
FORCEPROP 2 LAST CDS_LIB mstr_symbols
J 0
(-2850 2200);
PAINT ORANGE (-2850 2200);
DISPLAY INVISIBLE (-2850 2200);
FORCEPROP 1 LAST HDL_POWER GND
J 0
(-2850 2350);
PAINT GREEN (-2850 2350);
DISPLAY INVISIBLE (-2850 2350);
FORCEPROP 1 LAST PATH I44
J 0
(-2775 2200);
DISPLAY 0.872340 (-2775 2200);
PAINT AQUA (-2775 2200);
DISPLAY INVISIBLE (-2775 2200);
FORCEPROP 1 LAST SIZE 1B
J 0
(-2775 2150);
DISPLAY 1.127660 (-2775 2150);
PAINT ORANGE (-2775 2150);
DISPLAY INVISIBLE (-2775 2150);
FORCEADD RES..2
(-2675 1500);
FORCEPROP 1 LASTPIN (-2675 1400) $PN 2
J 0
(-2670 1410);
DISPLAY 0.617021 (-2670 1410);
PAINT ORANGE (-2670 1410);
FORCEPROP 1 LAST TOLERANCE 1%
J 0
(-2630 1525);
DISPLAY 0.617021 (-2630 1525);
PAINT SKYBLUE (-2630 1525);
FORCEPROP 1 LASTPIN (-2675 1600) $PN 1
J 0
(-2670 1562);
DISPLAY 0.617021 (-2670 1562);
PAINT ORANGE (-2670 1562);
FORCEPROP 1 LAST WATTAGE 1/16W
J 0
(-2635 1475);
DISPLAY 0.617021 (-2635 1475);
PAINT SKYBLUE (-2635 1475);
FORCEPROP 1 LAST MATERIAL CHIP
J 0
(-2635 1425);
DISPLAY 0.617021 (-2635 1425);
PAINT SKYBLUE (-2635 1425);
FORCEPROP 1 LAST PACK_TYPE 0402
J 0
(-2635 1325);
DISPLAY 0.617021 (-2635 1325);
PAINT SKYBLUE (-2635 1325);
FORCEPROP 1 LAST VALUE 4.75K
J 0
(-2630 1575);
DISPLAY 0.617021 (-2630 1575);
PAINT SKYBLUE (-2630 1575);
FORCEPROP 1 LAST PART_NUMBER G21796-072
J 0
(-2635 1375);
DISPLAY 0.617021 (-2635 1375);
PAINT BLUE (-2635 1375);
FORCEPROP 1 LAST LOCATION R4D40
J 0
(-2630 1625);
DISPLAY 0.617021 (-2630 1625);
PAINT AQUA (-2630 1625);
FORCEPROP 2 LAST CDS_LIB mstr_discrete
J 0
(-2675 1500);
PAINT ORANGE (-2675 1500);
DISPLAY INVISIBLE (-2675 1500);
FORCEPROP 2 LAST ROOM DB1200ZL
J 0
(-2625 1725);
DISPLAY 1.021277 (-2625 1725);
PAINT ORANGE (-2625 1725);
DISPLAY INVISIBLE (-2625 1725);
FORCEPROP 1 LAST PATH I45
J 0
(-2625 1675);
DISPLAY 0.978723 (-2625 1675);
PAINT WHITE (-2625 1675);
DISPLAY INVISIBLE (-2625 1675);
FORCEPROP 2 LAST CDS_LOCATION R4D40
J 0
(-2630 1625);
DISPLAY 0.617021 (-2630 1625);
PAINT AQUA (-2630 1625);
DISPLAY INVISIBLE (-2630 1625);
FORCEPROP 2 LAST SEC 1
J 0
(-2625 1725);
DISPLAY 0.680851 (-2625 1725);
PAINT MONO (-2625 1725);
DISPLAY INVISIBLE (-2625 1725);
FORCEPROP 2 LAST BOM_COST SYS_CLOCK
J 0
(-2625 1825);
DISPLAY 1.021277 (-2625 1825);
PAINT ORANGE (-2625 1825);
DISPLAY INVISIBLE (-2625 1825);
FORCEPROP 2 LAST SEC_TYPE 0402
J 0
(-2625 1725);
DISPLAY 1.021277 (-2625 1725);
PAINT ORANGE (-2625 1725);
DISPLAY INVISIBLE (-2625 1725);
FORCEADD RES..2
(-2675 1100);
FORCEPROP 1 LAST PACK_TYPE 0402
J 0
(-2635 925);
DISPLAY 0.617021 (-2635 925);
PAINT SKYBLUE (-2635 925);
FORCEPROP 1 LAST PART_NUMBER G21796-072
J 0
(-2635 975);
DISPLAY 0.617021 (-2635 975);
PAINT BLUE (-2635 975);
FORCEPROP 1 LASTPIN (-2675 1000) $PN 2
J 0
(-2670 1010);
DISPLAY 0.617021 (-2670 1010);
PAINT ORANGE (-2670 1010);
FORCEPROP 1 LAST TOLERANCE 1%
J 0
(-2630 1125);
DISPLAY 0.617021 (-2630 1125);
PAINT SKYBLUE (-2630 1125);
FORCEPROP 1 LASTPIN (-2675 1200) $PN 1
J 0
(-2670 1162);
DISPLAY 0.617021 (-2670 1162);
PAINT ORANGE (-2670 1162);
FORCEPROP 1 LAST VALUE 4.75K
J 0
(-2630 1175);
DISPLAY 0.617021 (-2630 1175);
PAINT SKYBLUE (-2630 1175);
FORCEPROP 1 LAST LOCATION R6P23
J 0
(-2630 1225);
DISPLAY 0.617021 (-2630 1225);
PAINT AQUA (-2630 1225);
FORCEPROP 1 LAST MATERIAL EMPTY
J 0
(-2635 1025);
DISPLAY 0.617021 (-2635 1025);
PAINT RED (-2635 1025);
FORCEPROP 1 LAST WATTAGE 1/16W
J 0
(-2635 1075);
DISPLAY 0.617021 (-2635 1075);
PAINT SKYBLUE (-2635 1075);
FORCEPROP 2 LAST CDS_LIB mstr_discrete
J 0
(-2675 1100);
PAINT ORANGE (-2675 1100);
DISPLAY INVISIBLE (-2675 1100);
FORCEPROP 2 LAST CDS_LOCATION R6P23
J 0
(-2630 1225);
DISPLAY 0.617021 (-2630 1225);
PAINT AQUA (-2630 1225);
DISPLAY INVISIBLE (-2630 1225);
FORCEPROP 1 LAST PATH I46
J 0
(-2625 1275);
DISPLAY 0.978723 (-2625 1275);
PAINT WHITE (-2625 1275);
DISPLAY INVISIBLE (-2625 1275);
FORCEPROP 2 LAST SEC_TYPE 0402
J 0
(-2625 1325);
DISPLAY 1.021277 (-2625 1325);
PAINT ORANGE (-2625 1325);
DISPLAY INVISIBLE (-2625 1325);
FORCEPROP 2 LAST BOM_COST SYS_CLOCK
J 0
(-2625 1425);
DISPLAY 1.021277 (-2625 1425);
PAINT ORANGE (-2625 1425);
DISPLAY INVISIBLE (-2625 1425);
FORCEPROP 2 LAST SEC 1
J 0
(-2625 1325);
DISPLAY 0.680851 (-2625 1325);
PAINT MONO (-2625 1325);
DISPLAY INVISIBLE (-2625 1325);
FORCEPROP 2 LAST ROOM DB1200ZL
J 0
(-2625 1325);
DISPLAY 1.021277 (-2625 1325);
PAINT ORANGE (-2625 1325);
DISPLAY INVISIBLE (-2625 1325);
FORCEADD RES..2
R 2
(-2925 1100);
FORCEPROP 1 LAST WATTAGE 1/16W
J 2
(-2965 1075);
DISPLAY 0.617021 (-2965 1075);
PAINT SKYBLUE (-2965 1075);
FORCEPROP 1 LAST PACK_TYPE 0402
J 2
(-2965 925);
DISPLAY 0.617021 (-2965 925);
PAINT SKYBLUE (-2965 925);
FORCEPROP 1 LAST VALUE 4.75K
J 2
(-2970 1175);
DISPLAY 0.617021 (-2970 1175);
PAINT SKYBLUE (-2970 1175);
FORCEPROP 1 LAST PART_NUMBER G21796-072
J 2
(-2965 975);
DISPLAY 0.617021 (-2965 975);
PAINT BLUE (-2965 975);
FORCEPROP 1 LAST LOCATION R6P22
J 2
(-2970 1225);
DISPLAY 0.617021 (-2970 1225);
PAINT AQUA (-2970 1225);
FORCEPROP 1 LAST MATERIAL EMPTY
J 2
(-2965 1025);
DISPLAY 0.617021 (-2965 1025);
PAINT RED (-2965 1025);
FORCEPROP 1 LASTPIN (-2925 1000) $PN 2
J 2
(-2930 1010);
DISPLAY 0.617021 (-2930 1010);
PAINT ORANGE (-2930 1010);
FORCEPROP 1 LAST TOLERANCE 1%
J 2
(-2970 1125);
DISPLAY 0.617021 (-2970 1125);
PAINT SKYBLUE (-2970 1125);
FORCEPROP 1 LASTPIN (-2925 1200) $PN 1
J 2
(-2930 1162);
DISPLAY 0.617021 (-2930 1162);
PAINT ORANGE (-2930 1162);
FORCEPROP 2 LAST CDS_LOCATION R6P22
J 2
(-2970 1225);
DISPLAY 0.617021 (-2970 1225);
PAINT AQUA (-2970 1225);
DISPLAY INVISIBLE (-2970 1225);
FORCEPROP 2 LAST CDS_LIB mstr_discrete
J 0
(-2925 1100);
PAINT MONO (-2925 1100);
DISPLAY INVISIBLE (-2925 1100);
FORCEPROP 1 LAST PATH I47
J 2
(-2975 1275);
DISPLAY 0.978723 (-2975 1275);
PAINT WHITE (-2975 1275);
DISPLAY INVISIBLE (-2975 1275);
FORCEPROP 2 LAST ROOM DB1200ZL
J 2
(-2975 1325);
DISPLAY 1.021277 (-2975 1325);
PAINT ORANGE (-2975 1325);
DISPLAY INVISIBLE (-2975 1325);
FORCEPROP 2 LAST SEC 1
J 0
(-2975 1325);
DISPLAY 0.680851 (-2975 1325);
PAINT MONO (-2975 1325);
DISPLAY INVISIBLE (-2975 1325);
FORCEPROP 2 LAST BOM_COST SYS_CLOCK
J 2
(-2975 1425);
DISPLAY 1.021277 (-2975 1425);
PAINT ORANGE (-2975 1425);
DISPLAY INVISIBLE (-2975 1425);
FORCEPROP 2 LAST SEC_TYPE 0402
J 0
(-2975 1325);
DISPLAY 1.021277 (-2975 1325);
PAINT ORANGE (-2975 1325);
DISPLAY INVISIBLE (-2975 1325);
FORCEADD VCC_CORE..1
(-2925 1875);
FORCEPROP 3 LASTPIN (-2925 1825) SIG_NAME P3V3_DB1200\g
J 0
(-2915 1835);
DISPLAY 0.659574 (-2915 1835);
PAINT MONO (-2915 1835);
DISPLAY INVISIBLE (-2915 1835);
FORCEPROP 1 LAST HDL_POWER P3V3_DB1200
J 1
(-2875 1925);
DISPLAY 0.617021 (-2875 1925);
PAINT GREEN (-2875 1925);
FORCEPROP 1 LAST PATH I49
J 0
(-2875 1900);
DISPLAY 0.872340 (-2875 1900);
PAINT AQUA (-2875 1900);
DISPLAY INVISIBLE (-2875 1900);
FORCEPROP 2 LAST CDS_LIB mstr_symbols
J 0
(-2925 1875);
PAINT ORANGE (-2925 1875);
DISPLAY INVISIBLE (-2925 1875);
FORCEPROP 0 LAST VOLTAGE 5
J 0
(-2925 1875);
PAINT SKYBLUE (-2925 1875);
DISPLAY INVISIBLE (-2925 1875);
FORCEADD OFFPAGE..1
(-1475 2375);
FORCEPROP 2 LAST $XR0 114 
J 0
(-1727 2375);
DISPLAY 0.638298 (-1727 2375);
PAINT MONO (-1727 2375);
FORCEPROP 1 LAST COMMENT_BODY TRUE
J 0
(-1350 2275);
DISPLAY 1.404255 (-1350 2275);
PAINT PEACH (-1350 2275);
DISPLAY INVISIBLE (-1350 2275);
FORCEPROP 2 LAST CDS_LIB mstr_standard
J 0
(-1475 2375);
PAINT ORANGE (-1475 2375);
DISPLAY INVISIBLE (-1475 2375);
FORCEPROP 2 LAST PATH I5
J 0
(-1425 2450);
DISPLAY 1.021277 (-1425 2450);
PAINT ORANGE (-1425 2450);
DISPLAY INVISIBLE (-1425 2450);
FORCEPROP 1 LAST OFFPAGE TRUE
J 0
(-1150 2250);
PAINT GREEN (-1150 2250);
DISPLAY INVISIBLE (-1150 2250);
FORCEADD GND..1
(-2675 775);
FORCEPROP 3 LASTPIN (-2675 825) SIG_NAME GND\g
J 0
(-2665 835);
DISPLAY 0.659574 (-2665 835);
PAINT MONO (-2665 835);
DISPLAY INVISIBLE (-2665 835);
FORCEPROP 2 LAST BOM_COST SYS_CLOCK
J 0
(-3125 850);
DISPLAY 1.617021 (-3125 850);
PAINT WHITE (-3125 850);
DISPLAY INVISIBLE (-3125 850);
FORCEPROP 2 LAST ROOM DB1200ZL
J 0
(-3000 850);
DISPLAY 1.127660 (-3000 850);
PAINT WHITE (-3000 850);
DISPLAY INVISIBLE (-3000 850);
FORCEPROP 1 LAST BODY_TYPE PLUMBING
J 0
(-2720 732);
DISPLAY 0.340426 (-2720 732);
PAINT GREEN (-2720 732);
DISPLAY INVISIBLE (-2720 732);
FORCEPROP 1 LAST VOLTAGE 0.0V
J 0
(-2720 732);
DISPLAY 0.340426 (-2720 732);
PAINT SKYBLUE (-2720 732);
DISPLAY INVISIBLE (-2720 732);
FORCEPROP 1 LAST SIZE 1B
J 0
(-2600 725);
DISPLAY 1.127660 (-2600 725);
PAINT ORANGE (-2600 725);
DISPLAY INVISIBLE (-2600 725);
FORCEPROP 2 LAST CDS_LIB mstr_symbols
J 0
(-2675 775);
PAINT ORANGE (-2675 775);
DISPLAY INVISIBLE (-2675 775);
FORCEPROP 1 LAST PATH I50
J 0
(-2600 775);
DISPLAY 0.872340 (-2600 775);
PAINT AQUA (-2600 775);
DISPLAY INVISIBLE (-2600 775);
FORCEPROP 1 LAST HDL_POWER GND
J 0
(-2675 925);
PAINT GREEN (-2675 925);
DISPLAY INVISIBLE (-2675 925);
FORCEADD OFFPAGE..2
(-1650 1325);
FORCEPROP 2 LAST $XR0 102 
J 0
(-1461 1325);
DISPLAY 0.638298 (-1461 1325);
PAINT MONO (-1461 1325);
FORCEPROP 1 LAST COMMENT_BODY TRUE
J 0
(-1695 1230);
DISPLAY 0.872340 (-1695 1230);
PAINT GREEN (-1695 1230);
DISPLAY INVISIBLE (-1695 1230);
FORCEPROP 2 LAST CDS_LIB mstr_standard
J 0
(-1650 1325);
PAINT ORANGE (-1650 1325);
DISPLAY INVISIBLE (-1650 1325);
FORCEPROP 1 LAST OFFPAGE TRUE
J 0
(-1325 1200);
DISPLAY 0.872340 (-1325 1200);
PAINT GREEN (-1325 1200);
DISPLAY INVISIBLE (-1325 1200);
FORCEPROP 2 LAST PATH I51
J 0
(-1475 1400);
DISPLAY 1.021277 (-1475 1400);
PAINT ORANGE (-1475 1400);
DISPLAY INVISIBLE (-1475 1400);
FORCEADD OFFPAGE..2
(-1650 1275);
FORCEPROP 2 LAST $XR0 102 
J 0
(-1461 1275);
DISPLAY 0.638298 (-1461 1275);
PAINT MONO (-1461 1275);
FORCEPROP 1 LAST COMMENT_BODY TRUE
J 0
(-1695 1180);
DISPLAY 0.872340 (-1695 1180);
PAINT GREEN (-1695 1180);
DISPLAY INVISIBLE (-1695 1180);
FORCEPROP 2 LAST CDS_LIB mstr_standard
J 0
(-1650 1275);
PAINT ORANGE (-1650 1275);
DISPLAY INVISIBLE (-1650 1275);
FORCEPROP 1 LAST OFFPAGE TRUE
J 0
(-1325 1150);
DISPLAY 0.872340 (-1325 1150);
PAINT GREEN (-1325 1150);
DISPLAY INVISIBLE (-1325 1150);
FORCEPROP 2 LAST PATH I52
J 0
(-1475 1350);
DISPLAY 1.021277 (-1475 1350);
PAINT ORANGE (-1475 1350);
DISPLAY INVISIBLE (-1475 1350);
FORCEADD RES..2
R 2
(-2925 1500);
FORCEPROP 1 LAST WATTAGE 1/16W
J 2
(-2965 1475);
DISPLAY 0.617021 (-2965 1475);
PAINT SKYBLUE (-2965 1475);
FORCEPROP 1 LAST MATERIAL CHIP
J 2
(-2965 1425);
DISPLAY 0.617021 (-2965 1425);
PAINT SKYBLUE (-2965 1425);
FORCEPROP 1 LAST PACK_TYPE 0402
J 2
(-2965 1325);
DISPLAY 0.617021 (-2965 1325);
PAINT SKYBLUE (-2965 1325);
FORCEPROP 1 LAST VALUE 4.75K
J 2
(-2970 1575);
DISPLAY 0.617021 (-2970 1575);
PAINT SKYBLUE (-2970 1575);
FORCEPROP 1 LAST PART_NUMBER G21796-072
J 2
(-2965 1375);
DISPLAY 0.617021 (-2965 1375);
PAINT BLUE (-2965 1375);
FORCEPROP 1 LAST LOCATION R4D41
J 2
(-2970 1625);
DISPLAY 0.617021 (-2970 1625);
PAINT AQUA (-2970 1625);
FORCEPROP 1 LASTPIN (-2925 1400) $PN 2
J 2
(-2930 1410);
DISPLAY 0.617021 (-2930 1410);
PAINT ORANGE (-2930 1410);
FORCEPROP 1 LAST TOLERANCE 1%
J 2
(-2970 1525);
DISPLAY 0.617021 (-2970 1525);
PAINT SKYBLUE (-2970 1525);
FORCEPROP 1 LASTPIN (-2925 1600) $PN 1
J 2
(-2930 1562);
DISPLAY 0.617021 (-2930 1562);
PAINT ORANGE (-2930 1562);
FORCEPROP 2 LAST CDS_LIB mstr_discrete
J 0
(-2925 1500);
PAINT MONO (-2925 1500);
DISPLAY INVISIBLE (-2925 1500);
FORCEPROP 2 LAST ROOM DB1200ZL
J 2
(-2975 1725);
DISPLAY 1.021277 (-2975 1725);
PAINT ORANGE (-2975 1725);
DISPLAY INVISIBLE (-2975 1725);
FORCEPROP 1 LAST PATH I53
J 2
(-2975 1675);
DISPLAY 0.978723 (-2975 1675);
PAINT WHITE (-2975 1675);
DISPLAY INVISIBLE (-2975 1675);
FORCEPROP 2 LAST CDS_LOCATION R4D41
J 2
(-2970 1625);
DISPLAY 0.617021 (-2970 1625);
PAINT AQUA (-2970 1625);
DISPLAY INVISIBLE (-2970 1625);
FORCEPROP 2 LAST SEC 1
J 0
(-2975 1725);
DISPLAY 0.680851 (-2975 1725);
PAINT MONO (-2975 1725);
DISPLAY INVISIBLE (-2975 1725);
FORCEPROP 2 LAST SEC_TYPE 0402
J 0
(-2975 1725);
DISPLAY 1.021277 (-2975 1725);
PAINT ORANGE (-2975 1725);
DISPLAY INVISIBLE (-2975 1725);
FORCEPROP 2 LAST BOM_COST SYS_CLOCK
J 2
(-2975 1825);
DISPLAY 1.021277 (-2975 1825);
PAINT ORANGE (-2975 1825);
DISPLAY INVISIBLE (-2975 1825);
FORCEADD OFFPAGE..2
(2025 3675);
FORCEPROP 2 LAST $XR0 103 
J 0
(2214 3675);
DISPLAY 0.638298 (2214 3675);
PAINT MONO (2214 3675);
FORCEPROP 1 LAST COMMENT_BODY TRUE
J 0
(1980 3580);
DISPLAY 0.872340 (1980 3580);
PAINT GREEN (1980 3580);
DISPLAY INVISIBLE (1980 3580);
FORCEPROP 2 LAST CDS_LIB mstr_standard
J 0
(2025 3675);
PAINT ORANGE (2025 3675);
DISPLAY INVISIBLE (2025 3675);
FORCEPROP 1 LAST OFFPAGE TRUE
J 0
(2350 3550);
DISPLAY 0.872340 (2350 3550);
PAINT GREEN (2350 3550);
DISPLAY INVISIBLE (2350 3550);
FORCEPROP 2 LAST PATH I54
J 0
(2200 3750);
DISPLAY 1.021277 (2200 3750);
PAINT ORANGE (2200 3750);
DISPLAY INVISIBLE (2200 3750);
FORCEADD OFFPAGE..2
(2025 3625);
FORCEPROP 2 LAST $XR0 103 
J 0
(2214 3625);
DISPLAY 0.638298 (2214 3625);
PAINT MONO (2214 3625);
FORCEPROP 1 LAST COMMENT_BODY TRUE
J 0
(1980 3530);
DISPLAY 0.872340 (1980 3530);
PAINT GREEN (1980 3530);
DISPLAY INVISIBLE (1980 3530);
FORCEPROP 2 LAST CDS_LIB mstr_standard
J 0
(2025 3625);
PAINT ORANGE (2025 3625);
DISPLAY INVISIBLE (2025 3625);
FORCEPROP 1 LAST OFFPAGE TRUE
J 0
(2350 3500);
DISPLAY 0.872340 (2350 3500);
PAINT GREEN (2350 3500);
DISPLAY INVISIBLE (2350 3500);
FORCEPROP 2 LAST PATH I55
J 0
(2200 3700);
DISPLAY 1.021277 (2200 3700);
PAINT ORANGE (2200 3700);
DISPLAY INVISIBLE (2200 3700);
FORCEADD OFFPAGE..2
(2025 3575);
FORCEPROP 2 LAST $XR0 103 
J 0
(2214 3575);
DISPLAY 0.638298 (2214 3575);
PAINT MONO (2214 3575);
FORCEPROP 1 LAST COMMENT_BODY TRUE
J 0
(1980 3480);
DISPLAY 0.872340 (1980 3480);
PAINT GREEN (1980 3480);
DISPLAY INVISIBLE (1980 3480);
FORCEPROP 2 LAST CDS_LIB mstr_standard
J 0
(2025 3575);
PAINT ORANGE (2025 3575);
DISPLAY INVISIBLE (2025 3575);
FORCEPROP 1 LAST OFFPAGE TRUE
J 0
(2350 3450);
DISPLAY 0.872340 (2350 3450);
PAINT GREEN (2350 3450);
DISPLAY INVISIBLE (2350 3450);
FORCEPROP 2 LAST PATH I56
J 0
(2200 3650);
DISPLAY 1.021277 (2200 3650);
PAINT ORANGE (2200 3650);
DISPLAY INVISIBLE (2200 3650);
FORCEADD OFFPAGE..2
(2025 3525);
FORCEPROP 2 LAST $XR0 103 
J 0
(2214 3525);
DISPLAY 0.638298 (2214 3525);
PAINT MONO (2214 3525);
FORCEPROP 1 LAST COMMENT_BODY TRUE
J 0
(1980 3430);
DISPLAY 0.872340 (1980 3430);
PAINT GREEN (1980 3430);
DISPLAY INVISIBLE (1980 3430);
FORCEPROP 2 LAST CDS_LIB mstr_standard
J 0
(2025 3525);
PAINT ORANGE (2025 3525);
DISPLAY INVISIBLE (2025 3525);
FORCEPROP 1 LAST OFFPAGE TRUE
J 0
(2350 3400);
DISPLAY 0.872340 (2350 3400);
PAINT GREEN (2350 3400);
DISPLAY INVISIBLE (2350 3400);
FORCEPROP 2 LAST PATH I57
J 0
(2200 3600);
DISPLAY 1.021277 (2200 3600);
PAINT ORANGE (2200 3600);
DISPLAY INVISIBLE (2200 3600);
FORCEADD OFFPAGE..2
(2025 3475);
FORCEPROP 2 LAST $XR0 103 
J 0
(2214 3475);
DISPLAY 0.638298 (2214 3475);
PAINT MONO (2214 3475);
FORCEPROP 1 LAST COMMENT_BODY TRUE
J 0
(1980 3380);
DISPLAY 0.872340 (1980 3380);
PAINT GREEN (1980 3380);
DISPLAY INVISIBLE (1980 3380);
FORCEPROP 2 LAST CDS_LIB mstr_standard
J 0
(2025 3475);
PAINT ORANGE (2025 3475);
DISPLAY INVISIBLE (2025 3475);
FORCEPROP 1 LAST OFFPAGE TRUE
J 0
(2350 3350);
DISPLAY 0.872340 (2350 3350);
PAINT GREEN (2350 3350);
DISPLAY INVISIBLE (2350 3350);
FORCEPROP 2 LAST PATH I58
J 0
(2200 3550);
DISPLAY 1.021277 (2200 3550);
PAINT ORANGE (2200 3550);
DISPLAY INVISIBLE (2200 3550);
FORCEADD OFFPAGE..2
(2025 3425);
FORCEPROP 2 LAST $XR0 103 
J 0
(2214 3425);
DISPLAY 0.638298 (2214 3425);
PAINT MONO (2214 3425);
FORCEPROP 1 LAST COMMENT_BODY TRUE
J 0
(1980 3330);
DISPLAY 0.872340 (1980 3330);
PAINT GREEN (1980 3330);
DISPLAY INVISIBLE (1980 3330);
FORCEPROP 2 LAST CDS_LIB mstr_standard
J 0
(2025 3425);
PAINT ORANGE (2025 3425);
DISPLAY INVISIBLE (2025 3425);
FORCEPROP 2 LAST PATH I59
J 0
(2200 3500);
DISPLAY 1.021277 (2200 3500);
PAINT ORANGE (2200 3500);
DISPLAY INVISIBLE (2200 3500);
FORCEPROP 1 LAST OFFPAGE TRUE
J 0
(2350 3300);
DISPLAY 0.872340 (2350 3300);
PAINT GREEN (2350 3300);
DISPLAY INVISIBLE (2350 3300);
FORCEADD GND..1
(1425 1800);
FORCEPROP 3 LASTPIN (1425 1850) SIG_NAME GND\g
J 0
(1435 1860);
DISPLAY 0.659574 (1435 1860);
PAINT MONO (1435 1860);
DISPLAY INVISIBLE (1435 1860);
FORCEPROP 2 LAST BOM_COST SYS_CLOCK
J 0
(975 1875);
DISPLAY 1.617021 (975 1875);
PAINT WHITE (975 1875);
DISPLAY INVISIBLE (975 1875);
FORCEPROP 2 LAST ROOM DB1200ZL
J 0
(1100 1875);
DISPLAY 1.127660 (1100 1875);
PAINT WHITE (1100 1875);
DISPLAY INVISIBLE (1100 1875);
FORCEPROP 1 LAST BODY_TYPE PLUMBING
J 0
(1380 1757);
DISPLAY 0.340426 (1380 1757);
PAINT GREEN (1380 1757);
DISPLAY INVISIBLE (1380 1757);
FORCEPROP 1 LAST VOLTAGE 0.0V
J 0
(1380 1757);
DISPLAY 0.340426 (1380 1757);
PAINT SKYBLUE (1380 1757);
DISPLAY INVISIBLE (1380 1757);
FORCEPROP 1 LAST SIZE 1B
J 0
(1500 1750);
DISPLAY 1.127660 (1500 1750);
PAINT ORANGE (1500 1750);
DISPLAY INVISIBLE (1500 1750);
FORCEPROP 1 LAST PATH I6
J 0
(1500 1800);
DISPLAY 0.872340 (1500 1800);
PAINT AQUA (1500 1800);
DISPLAY INVISIBLE (1500 1800);
FORCEPROP 2 LAST CDS_LIB mstr_symbols
J 0
(1425 1800);
PAINT ORANGE (1425 1800);
DISPLAY INVISIBLE (1425 1800);
FORCEPROP 1 LAST HDL_POWER GND
J 0
(1425 1950);
PAINT GREEN (1425 1950);
DISPLAY INVISIBLE (1425 1950);
FORCEADD OFFPAGE..2
(2025 3375);
FORCEPROP 2 LAST $XR0 103 
J 0
(2214 3375);
DISPLAY 0.638298 (2214 3375);
PAINT MONO (2214 3375);
FORCEPROP 1 LAST COMMENT_BODY TRUE
J 0
(1980 3280);
DISPLAY 0.872340 (1980 3280);
PAINT GREEN (1980 3280);
DISPLAY INVISIBLE (1980 3280);
FORCEPROP 2 LAST CDS_LIB mstr_standard
J 0
(2025 3375);
PAINT ORANGE (2025 3375);
DISPLAY INVISIBLE (2025 3375);
FORCEPROP 2 LAST PATH I60
J 0
(2200 3450);
DISPLAY 1.021277 (2200 3450);
PAINT ORANGE (2200 3450);
DISPLAY INVISIBLE (2200 3450);
FORCEPROP 1 LAST OFFPAGE TRUE
J 0
(2350 3250);
DISPLAY 0.872340 (2350 3250);
PAINT GREEN (2350 3250);
DISPLAY INVISIBLE (2350 3250);
FORCEADD OFFPAGE..2
(2025 3325);
FORCEPROP 2 LAST $XR0 103 
J 0
(2214 3325);
DISPLAY 0.638298 (2214 3325);
PAINT MONO (2214 3325);
FORCEPROP 1 LAST COMMENT_BODY TRUE
J 0
(1980 3230);
DISPLAY 0.872340 (1980 3230);
PAINT GREEN (1980 3230);
DISPLAY INVISIBLE (1980 3230);
FORCEPROP 2 LAST CDS_LIB mstr_standard
J 0
(2025 3325);
PAINT ORANGE (2025 3325);
DISPLAY INVISIBLE (2025 3325);
FORCEPROP 2 LAST PATH I61
J 0
(2200 3400);
DISPLAY 1.021277 (2200 3400);
PAINT ORANGE (2200 3400);
DISPLAY INVISIBLE (2200 3400);
FORCEPROP 1 LAST OFFPAGE TRUE
J 0
(2350 3200);
DISPLAY 0.872340 (2350 3200);
PAINT GREEN (2350 3200);
DISPLAY INVISIBLE (2350 3200);
FORCEADD OFFPAGE..2
(2025 3275);
FORCEPROP 2 LAST $XR0 103 
J 0
(2214 3275);
DISPLAY 0.638298 (2214 3275);
PAINT MONO (2214 3275);
FORCEPROP 1 LAST COMMENT_BODY TRUE
J 0
(1980 3180);
DISPLAY 0.872340 (1980 3180);
PAINT GREEN (1980 3180);
DISPLAY INVISIBLE (1980 3180);
FORCEPROP 2 LAST CDS_LIB mstr_standard
J 0
(2025 3275);
PAINT ORANGE (2025 3275);
DISPLAY INVISIBLE (2025 3275);
FORCEPROP 2 LAST PATH I62
J 0
(2200 3350);
DISPLAY 1.021277 (2200 3350);
PAINT ORANGE (2200 3350);
DISPLAY INVISIBLE (2200 3350);
FORCEPROP 1 LAST OFFPAGE TRUE
J 0
(2350 3150);
DISPLAY 0.872340 (2350 3150);
PAINT GREEN (2350 3150);
DISPLAY INVISIBLE (2350 3150);
FORCEADD OFFPAGE..2
(2025 3225);
FORCEPROP 2 LAST $XR0 103 
J 0
(2214 3225);
DISPLAY 0.638298 (2214 3225);
PAINT MONO (2214 3225);
FORCEPROP 1 LAST COMMENT_BODY TRUE
J 0
(1980 3130);
DISPLAY 0.872340 (1980 3130);
PAINT GREEN (1980 3130);
DISPLAY INVISIBLE (1980 3130);
FORCEPROP 2 LAST CDS_LIB mstr_standard
J 0
(2025 3225);
PAINT ORANGE (2025 3225);
DISPLAY INVISIBLE (2025 3225);
FORCEPROP 2 LAST PATH I63
J 0
(2200 3300);
DISPLAY 1.021277 (2200 3300);
PAINT ORANGE (2200 3300);
DISPLAY INVISIBLE (2200 3300);
FORCEPROP 1 LAST OFFPAGE TRUE
J 0
(2350 3100);
DISPLAY 0.872340 (2350 3100);
PAINT GREEN (2350 3100);
DISPLAY INVISIBLE (2350 3100);
FORCEADD OFFPAGE..2
(2025 3175);
FORCEPROP 2 LAST $XR0 103 
J 0
(2214 3175);
DISPLAY 0.638298 (2214 3175);
PAINT MONO (2214 3175);
FORCEPROP 1 LAST COMMENT_BODY TRUE
J 0
(1980 3080);
DISPLAY 0.872340 (1980 3080);
PAINT GREEN (1980 3080);
DISPLAY INVISIBLE (1980 3080);
FORCEPROP 2 LAST CDS_LIB mstr_standard
J 0
(2025 3175);
PAINT ORANGE (2025 3175);
DISPLAY INVISIBLE (2025 3175);
FORCEPROP 1 LAST OFFPAGE TRUE
J 0
(2350 3050);
DISPLAY 0.872340 (2350 3050);
PAINT GREEN (2350 3050);
DISPLAY INVISIBLE (2350 3050);
FORCEPROP 2 LAST PATH I64
J 0
(2200 3250);
DISPLAY 1.021277 (2200 3250);
PAINT ORANGE (2200 3250);
DISPLAY INVISIBLE (2200 3250);
FORCEADD OFFPAGE..2
(2025 3125);
FORCEPROP 2 LAST $XR0 103 
J 0
(2214 3125);
DISPLAY 0.638298 (2214 3125);
PAINT MONO (2214 3125);
FORCEPROP 1 LAST COMMENT_BODY TRUE
J 0
(1980 3030);
DISPLAY 0.872340 (1980 3030);
PAINT GREEN (1980 3030);
DISPLAY INVISIBLE (1980 3030);
FORCEPROP 2 LAST CDS_LIB mstr_standard
J 0
(2025 3125);
PAINT ORANGE (2025 3125);
DISPLAY INVISIBLE (2025 3125);
FORCEPROP 1 LAST OFFPAGE TRUE
J 0
(2350 3000);
DISPLAY 0.872340 (2350 3000);
PAINT GREEN (2350 3000);
DISPLAY INVISIBLE (2350 3000);
FORCEPROP 2 LAST PATH I65
J 0
(2200 3200);
DISPLAY 1.021277 (2200 3200);
PAINT ORANGE (2200 3200);
DISPLAY INVISIBLE (2200 3200);
FORCEADD OFFPAGE..2
(2025 3075);
FORCEPROP 2 LAST $XR0 103 
J 0
(2214 3075);
DISPLAY 0.638298 (2214 3075);
PAINT MONO (2214 3075);
FORCEPROP 1 LAST COMMENT_BODY TRUE
J 0
(1980 2980);
DISPLAY 0.872340 (1980 2980);
PAINT GREEN (1980 2980);
DISPLAY INVISIBLE (1980 2980);
FORCEPROP 2 LAST CDS_LIB mstr_standard
J 0
(2025 3075);
PAINT ORANGE (2025 3075);
DISPLAY INVISIBLE (2025 3075);
FORCEPROP 1 LAST OFFPAGE TRUE
J 0
(2350 2950);
DISPLAY 0.872340 (2350 2950);
PAINT GREEN (2350 2950);
DISPLAY INVISIBLE (2350 2950);
FORCEPROP 2 LAST PATH I66
J 0
(2200 3150);
DISPLAY 1.021277 (2200 3150);
PAINT ORANGE (2200 3150);
DISPLAY INVISIBLE (2200 3150);
FORCEADD OFFPAGE..2
(2025 3025);
FORCEPROP 2 LAST $XR0 103 
J 0
(2214 3025);
DISPLAY 0.638298 (2214 3025);
PAINT MONO (2214 3025);
FORCEPROP 1 LAST COMMENT_BODY TRUE
J 0
(1980 2930);
DISPLAY 0.872340 (1980 2930);
PAINT GREEN (1980 2930);
DISPLAY INVISIBLE (1980 2930);
FORCEPROP 2 LAST CDS_LIB mstr_standard
J 0
(2025 3025);
PAINT ORANGE (2025 3025);
DISPLAY INVISIBLE (2025 3025);
FORCEPROP 1 LAST OFFPAGE TRUE
J 0
(2350 2900);
DISPLAY 0.872340 (2350 2900);
PAINT GREEN (2350 2900);
DISPLAY INVISIBLE (2350 2900);
FORCEPROP 2 LAST PATH I67
J 0
(2200 3100);
DISPLAY 1.021277 (2200 3100);
PAINT ORANGE (2200 3100);
DISPLAY INVISIBLE (2200 3100);
FORCEADD OFFPAGE..2
(2025 2975);
FORCEPROP 2 LAST $XR0 103 
J 0
(2214 2975);
DISPLAY 0.638298 (2214 2975);
PAINT MONO (2214 2975);
FORCEPROP 1 LAST COMMENT_BODY TRUE
J 0
(1980 2880);
DISPLAY 0.872340 (1980 2880);
PAINT GREEN (1980 2880);
DISPLAY INVISIBLE (1980 2880);
FORCEPROP 2 LAST CDS_LIB mstr_standard
J 0
(2025 2975);
PAINT ORANGE (2025 2975);
DISPLAY INVISIBLE (2025 2975);
FORCEPROP 1 LAST OFFPAGE TRUE
J 0
(2350 2850);
DISPLAY 0.872340 (2350 2850);
PAINT GREEN (2350 2850);
DISPLAY INVISIBLE (2350 2850);
FORCEPROP 2 LAST PATH I68
J 0
(2200 3050);
DISPLAY 1.021277 (2200 3050);
PAINT ORANGE (2200 3050);
DISPLAY INVISIBLE (2200 3050);
FORCEADD OFFPAGE..2
(2025 2925);
FORCEPROP 2 LAST $XR0 103 
J 0
(2214 2925);
DISPLAY 0.638298 (2214 2925);
PAINT MONO (2214 2925);
FORCEPROP 1 LAST COMMENT_BODY TRUE
J 0
(1980 2830);
DISPLAY 0.872340 (1980 2830);
PAINT GREEN (1980 2830);
DISPLAY INVISIBLE (1980 2830);
FORCEPROP 2 LAST CDS_LIB mstr_standard
J 0
(2025 2925);
PAINT ORANGE (2025 2925);
DISPLAY INVISIBLE (2025 2925);
FORCEPROP 2 LAST PATH I69
J 0
(2200 3000);
DISPLAY 1.021277 (2200 3000);
PAINT ORANGE (2200 3000);
DISPLAY INVISIBLE (2200 3000);
FORCEPROP 1 LAST OFFPAGE TRUE
J 0
(2350 2800);
DISPLAY 0.872340 (2350 2800);
PAINT GREEN (2350 2800);
DISPLAY INVISIBLE (2350 2800);
FORCEADD OFFPAGE..1
(-1475 2275);
FORCEPROP 2 LAST $XR0 191 
J 0
(-1727 2275);
DISPLAY 0.638298 (-1727 2275);
PAINT MONO (-1727 2275);
FORCEPROP 1 LAST COMMENT_BODY TRUE
J 0
(-1350 2175);
DISPLAY 1.404255 (-1350 2175);
PAINT PEACH (-1350 2175);
DISPLAY INVISIBLE (-1350 2175);
FORCEPROP 2 LAST CDS_LIB mstr_standard
J 0
(-1475 2275);
PAINT ORANGE (-1475 2275);
DISPLAY INVISIBLE (-1475 2275);
FORCEPROP 2 LAST PATH I7
J 0
(-1425 2350);
DISPLAY 1.021277 (-1425 2350);
PAINT ORANGE (-1425 2350);
DISPLAY INVISIBLE (-1425 2350);
FORCEPROP 1 LAST OFFPAGE TRUE
J 0
(-1150 2150);
PAINT GREEN (-1150 2150);
DISPLAY INVISIBLE (-1150 2150);
FORCEADD OFFPAGE..2
(2025 2875);
FORCEPROP 2 LAST $XR0 103 
J 0
(2214 2875);
DISPLAY 0.638298 (2214 2875);
PAINT MONO (2214 2875);
FORCEPROP 1 LAST COMMENT_BODY TRUE
J 0
(1980 2780);
DISPLAY 0.872340 (1980 2780);
PAINT GREEN (1980 2780);
DISPLAY INVISIBLE (1980 2780);
FORCEPROP 2 LAST CDS_LIB mstr_standard
J 0
(2025 2875);
PAINT ORANGE (2025 2875);
DISPLAY INVISIBLE (2025 2875);
FORCEPROP 2 LAST PATH I70
J 0
(2200 2950);
DISPLAY 1.021277 (2200 2950);
PAINT ORANGE (2200 2950);
DISPLAY INVISIBLE (2200 2950);
FORCEPROP 1 LAST OFFPAGE TRUE
J 0
(2350 2750);
DISPLAY 0.872340 (2350 2750);
PAINT GREEN (2350 2750);
DISPLAY INVISIBLE (2350 2750);
FORCEADD OFFPAGE..2
(2025 2825);
FORCEPROP 2 LAST $XR0 103 
J 0
(2214 2825);
DISPLAY 0.638298 (2214 2825);
PAINT MONO (2214 2825);
FORCEPROP 1 LAST COMMENT_BODY TRUE
J 0
(1980 2730);
DISPLAY 0.872340 (1980 2730);
PAINT GREEN (1980 2730);
DISPLAY INVISIBLE (1980 2730);
FORCEPROP 2 LAST CDS_LIB mstr_standard
J 0
(2025 2825);
PAINT ORANGE (2025 2825);
DISPLAY INVISIBLE (2025 2825);
FORCEPROP 2 LAST PATH I71
J 0
(2200 2900);
DISPLAY 1.021277 (2200 2900);
PAINT ORANGE (2200 2900);
DISPLAY INVISIBLE (2200 2900);
FORCEPROP 1 LAST OFFPAGE TRUE
J 0
(2350 2700);
DISPLAY 0.872340 (2350 2700);
PAINT GREEN (2350 2700);
DISPLAY INVISIBLE (2350 2700);
FORCEADD OFFPAGE..2
(2025 2775);
FORCEPROP 2 LAST $XR0 103 
J 0
(2214 2775);
DISPLAY 0.638298 (2214 2775);
PAINT MONO (2214 2775);
FORCEPROP 1 LAST COMMENT_BODY TRUE
J 0
(1980 2680);
DISPLAY 0.872340 (1980 2680);
PAINT GREEN (1980 2680);
DISPLAY INVISIBLE (1980 2680);
FORCEPROP 2 LAST CDS_LIB mstr_standard
J 0
(2025 2775);
PAINT ORANGE (2025 2775);
DISPLAY INVISIBLE (2025 2775);
FORCEPROP 2 LAST PATH I72
J 0
(2200 2850);
DISPLAY 1.021277 (2200 2850);
PAINT ORANGE (2200 2850);
DISPLAY INVISIBLE (2200 2850);
FORCEPROP 1 LAST OFFPAGE TRUE
J 0
(2350 2650);
DISPLAY 0.872340 (2350 2650);
PAINT GREEN (2350 2650);
DISPLAY INVISIBLE (2350 2650);
FORCEADD OFFPAGE..2
(2025 2725);
FORCEPROP 2 LAST $XR0 103 
J 0
(2214 2725);
DISPLAY 0.638298 (2214 2725);
PAINT MONO (2214 2725);
FORCEPROP 1 LAST COMMENT_BODY TRUE
J 0
(1980 2630);
DISPLAY 0.872340 (1980 2630);
PAINT GREEN (1980 2630);
DISPLAY INVISIBLE (1980 2630);
FORCEPROP 2 LAST CDS_LIB mstr_standard
J 0
(2025 2725);
PAINT ORANGE (2025 2725);
DISPLAY INVISIBLE (2025 2725);
FORCEPROP 2 LAST PATH I73
J 0
(2200 2800);
DISPLAY 1.021277 (2200 2800);
PAINT ORANGE (2200 2800);
DISPLAY INVISIBLE (2200 2800);
FORCEPROP 1 LAST OFFPAGE TRUE
J 0
(2350 2600);
DISPLAY 0.872340 (2350 2600);
PAINT GREEN (2350 2600);
DISPLAY INVISIBLE (2350 2600);
FORCEADD OFFPAGE..2
(2025 2675);
FORCEPROP 2 LAST $XR0 103 
J 0
(2214 2675);
DISPLAY 0.638298 (2214 2675);
PAINT MONO (2214 2675);
FORCEPROP 1 LAST COMMENT_BODY TRUE
J 0
(1980 2580);
DISPLAY 0.872340 (1980 2580);
PAINT GREEN (1980 2580);
DISPLAY INVISIBLE (1980 2580);
FORCEPROP 2 LAST CDS_LIB mstr_standard
J 0
(2025 2675);
PAINT ORANGE (2025 2675);
DISPLAY INVISIBLE (2025 2675);
FORCEPROP 1 LAST OFFPAGE TRUE
J 0
(2350 2550);
DISPLAY 0.872340 (2350 2550);
PAINT GREEN (2350 2550);
DISPLAY INVISIBLE (2350 2550);
FORCEPROP 2 LAST PATH I74
J 0
(2200 2750);
DISPLAY 1.021277 (2200 2750);
PAINT ORANGE (2200 2750);
DISPLAY INVISIBLE (2200 2750);
FORCEADD OFFPAGE..2
(2025 2625);
FORCEPROP 2 LAST $XR0 103 
J 0
(2214 2625);
DISPLAY 0.638298 (2214 2625);
PAINT MONO (2214 2625);
FORCEPROP 1 LAST COMMENT_BODY TRUE
J 0
(1980 2530);
DISPLAY 0.872340 (1980 2530);
PAINT GREEN (1980 2530);
DISPLAY INVISIBLE (1980 2530);
FORCEPROP 2 LAST CDS_LIB mstr_standard
J 0
(2025 2625);
PAINT ORANGE (2025 2625);
DISPLAY INVISIBLE (2025 2625);
FORCEPROP 1 LAST OFFPAGE TRUE
J 0
(2350 2500);
DISPLAY 0.872340 (2350 2500);
PAINT GREEN (2350 2500);
DISPLAY INVISIBLE (2350 2500);
FORCEPROP 2 LAST PATH I75
J 0
(2200 2700);
DISPLAY 1.021277 (2200 2700);
PAINT ORANGE (2200 2700);
DISPLAY INVISIBLE (2200 2700);
FORCEADD OFFPAGE..2
(2025 2575);
FORCEPROP 2 LAST $XR0 103 
J 0
(2214 2575);
DISPLAY 0.638298 (2214 2575);
PAINT MONO (2214 2575);
FORCEPROP 1 LAST COMMENT_BODY TRUE
J 0
(1980 2480);
DISPLAY 0.872340 (1980 2480);
PAINT GREEN (1980 2480);
DISPLAY INVISIBLE (1980 2480);
FORCEPROP 2 LAST CDS_LIB mstr_standard
J 0
(2025 2575);
PAINT ORANGE (2025 2575);
DISPLAY INVISIBLE (2025 2575);
FORCEPROP 1 LAST OFFPAGE TRUE
J 0
(2350 2450);
DISPLAY 0.872340 (2350 2450);
PAINT GREEN (2350 2450);
DISPLAY INVISIBLE (2350 2450);
FORCEPROP 2 LAST PATH I76
J 0
(2200 2650);
DISPLAY 1.021277 (2200 2650);
PAINT ORANGE (2200 2650);
DISPLAY INVISIBLE (2200 2650);
FORCEADD OFFPAGE..2
(2025 2525);
FORCEPROP 2 LAST $XR0 103 
J 0
(2214 2525);
DISPLAY 0.638298 (2214 2525);
PAINT MONO (2214 2525);
FORCEPROP 1 LAST COMMENT_BODY TRUE
J 0
(1980 2430);
DISPLAY 0.872340 (1980 2430);
PAINT GREEN (1980 2430);
DISPLAY INVISIBLE (1980 2430);
FORCEPROP 2 LAST CDS_LIB mstr_standard
J 0
(2025 2525);
PAINT ORANGE (2025 2525);
DISPLAY INVISIBLE (2025 2525);
FORCEPROP 1 LAST OFFPAGE TRUE
J 0
(2350 2400);
DISPLAY 0.872340 (2350 2400);
PAINT GREEN (2350 2400);
DISPLAY INVISIBLE (2350 2400);
FORCEPROP 2 LAST PATH I77
J 0
(2200 2600);
DISPLAY 1.021277 (2200 2600);
PAINT ORANGE (2200 2600);
DISPLAY INVISIBLE (2200 2600);
FORCEADD CAP_A..1
(2275 975);
FORCEPROP 1 LASTPIN (2275 875) $PN 2
J 0
(2285 855);
DISPLAY 0.617021 (2285 855);
PAINT ORANGE (2285 855);
FORCEPROP 1 LAST PACK_TYPE 0402V
J 0
(2325 775);
DISPLAY 0.617021 (2325 775);
PAINT SKYBLUE (2325 775);
FORCEPROP 1 LAST TOLERANCE 10%
J 0
(2325 925);
DISPLAY 0.617021 (2325 925);
PAINT SKYBLUE (2325 925);
FORCEPROP 1 LAST MATERIAL X7R
J 0
(2325 875);
DISPLAY 0.617021 (2325 875);
PAINT SKYBLUE (2325 875);
FORCEPROP 1 LAST VOLTAGE 16V
J 0
(2325 975);
DISPLAY 0.617021 (2325 975);
PAINT SKYBLUE (2325 975);
FORCEPROP 1 LAST PART_NUMBER A36096-030
J 0
(2325 825);
DISPLAY 0.617021 (2325 825);
PAINT BLUE (2325 825);
FORCEPROP 1 LASTPIN (2275 1075) $PN 1
J 0
(2285 1055);
DISPLAY 0.617021 (2285 1055);
PAINT ORANGE (2285 1055);
FORCEPROP 1 LAST VALUE 0.1UF
J 0
(2325 1025);
DISPLAY 0.617021 (2325 1025);
PAINT SKYBLUE (2325 1025);
FORCEPROP 1 LAST LOCATION C6P9
J 0
(2325 1075);
DISPLAY 0.617021 (2325 1075);
PAINT AQUA (2325 1075);
FORCEPROP 2 LAST CDS_LIB dev_discrete
J 0
(2275 975);
PAINT ORANGE (2275 975);
DISPLAY INVISIBLE (2275 975);
FORCEPROP 2 LAST SEC_TYPE 0402V
J 0
(2325 1175);
DISPLAY 1.021277 (2325 1175);
PAINT ORANGE (2325 1175);
DISPLAY INVISIBLE (2325 1175);
FORCEPROP 1 LAST PATH I79
J 0
(2325 1125);
DISPLAY 0.978723 (2325 1125);
PAINT WHITE (2325 1125);
DISPLAY INVISIBLE (2325 1125);
FORCEPROP 2 LAST ROOM DB1200ZL
J 0
(2325 1175);
DISPLAY 1.021277 (2325 1175);
PAINT ORANGE (2325 1175);
DISPLAY INVISIBLE (2325 1175);
FORCEPROP 2 LAST SEC 1
J 0
(2325 1175);
DISPLAY 0.680851 (2325 1175);
PAINT MONO (2325 1175);
DISPLAY INVISIBLE (2325 1175);
FORCEPROP 2 LAST CDS_LOCATION C6P9
J 0
(2325 1075);
DISPLAY 0.617021 (2325 1075);
PAINT AQUA (2325 1075);
DISPLAY INVISIBLE (2325 1075);
FORCEPROP 2 LAST BOM_COST SYS_CLOCK
J 0
(2325 1275);
DISPLAY 1.021277 (2325 1275);
PAINT ORANGE (2325 1275);
DISPLAY INVISIBLE (2325 1275);
FORCEPROP 2 LAST CDS_SEC 1
J 0
(2325 1125);
PAINT ORANGE (2325 1125);
DISPLAY INVISIBLE (2325 1125);
FORCEADD FERRITE..1
(1700 1200);
FORCEPROP 1 LASTPIN (1600 1200) $PN 1
J 2
(1635 1210);
DISPLAY 0.617021 (1635 1210);
PAINT WHITE (1635 1210);
FORCEPROP 1 LAST VALUE 600
J 2
(1705 1100);
DISPLAY 0.617021 (1705 1100);
PAINT SKYBLUE (1705 1100);
FORCEPROP 1 LAST PACK_TYPE SMLF
J 0
(1605 1050);
DISPLAY 0.617021 (1605 1050);
PAINT SKYBLUE (1605 1050);
FORCEPROP 1 LAST LOCATION FB6P1
J 0
(1605 1255);
DISPLAY 0.617021 (1605 1255);
PAINT AQUA (1605 1255);
FORCEPROP 1 LASTPIN (1800 1200) $PN 2
J 0
(1780 1210);
DISPLAY 0.617021 (1780 1210);
PAINT WHITE (1780 1210);
FORCEPROP 1 LAST MATERIAL FB
J 0
(1755 1100);
DISPLAY 0.617021 (1755 1100);
PAINT SKYBLUE (1755 1100);
FORCEPROP 1 LAST PART_NUMBER 656554-043
J 0
(1605 1315);
DISPLAY 0.617021 (1605 1315);
PAINT BLUE (1605 1315);
FORCEPROP 2 LAST CDS_LIB mstr_discrete
J 0
(1700 1200);
PAINT ORANGE (1700 1200);
DISPLAY INVISIBLE (1700 1200);
FORCEPROP 2 LAST CDS_LOCATION FB6P1
J 0
(1605 1255);
DISPLAY 0.617021 (1605 1255);
PAINT AQUA (1605 1255);
DISPLAY INVISIBLE (1605 1255);
FORCEPROP 2 LAST BOM_COST SYS_CLOCK
J 0
(1625 1400);
DISPLAY 1.021277 (1625 1400);
PAINT ORANGE (1625 1400);
DISPLAY INVISIBLE (1625 1400);
FORCEPROP 2 LAST SEC_TYPE SMLF
J 0
(1625 1425);
DISPLAY 1.021277 (1625 1425);
PAINT ORANGE (1625 1425);
DISPLAY INVISIBLE (1625 1425);
FORCEPROP 2 LAST SEC 1
J 0
(1625 1425);
DISPLAY 0.680851 (1625 1425);
PAINT MONO (1625 1425);
DISPLAY INVISIBLE (1625 1425);
FORCEPROP 1 LAST PATH I8
J 0
(1605 1365);
DISPLAY 0.872340 (1605 1365);
PAINT PURPLE (1605 1365);
DISPLAY INVISIBLE (1605 1365);
FORCEPROP 2 LAST ROOM DB1200ZL
J 0
(1625 1400);
DISPLAY 1.021277 (1625 1400);
PAINT ORANGE (1625 1400);
DISPLAY INVISIBLE (1625 1400);
FORCEADD RES..2
(-3225 2550);
FORCEPROP 1 LASTPIN (-3225 2450) $PN 2
J 0
(-3220 2460);
DISPLAY 0.617021 (-3220 2460);
PAINT ORANGE (-3220 2460);
FORCEPROP 1 LASTPIN (-3225 2650) $PN 1
J 0
(-3220 2612);
DISPLAY 0.617021 (-3220 2612);
PAINT ORANGE (-3220 2612);
FORCEPROP 1 LAST TOLERANCE 1%
J 0
(-3180 2575);
DISPLAY 0.617021 (-3180 2575);
PAINT SKYBLUE (-3180 2575);
FORCEPROP 1 LAST WATTAGE 1/16W
J 0
(-3185 2525);
DISPLAY 0.617021 (-3185 2525);
PAINT SKYBLUE (-3185 2525);
FORCEPROP 1 LAST MATERIAL CHIP
J 0
(-3185 2475);
DISPLAY 0.617021 (-3185 2475);
PAINT SKYBLUE (-3185 2475);
FORCEPROP 1 LAST PACK_TYPE 0402
J 0
(-3185 2375);
DISPLAY 0.617021 (-3185 2375);
PAINT SKYBLUE (-3185 2375);
FORCEPROP 1 LAST VALUE 1.00K
J 0
(-3180 2625);
DISPLAY 0.617021 (-3180 2625);
PAINT SKYBLUE (-3180 2625);
FORCEPROP 1 LAST PART_NUMBER G21796-026
J 0
(-3185 2425);
DISPLAY 0.617021 (-3185 2425);
PAINT BLUE (-3185 2425);
FORCEPROP 1 LAST LOCATION R6P21
J 0
(-3180 2675);
DISPLAY 0.617021 (-3180 2675);
PAINT AQUA (-3180 2675);
FORCEPROP 2 LAST CDS_LIB mstr_discrete
J 0
(-3225 2550);
PAINT ORANGE (-3225 2550);
DISPLAY INVISIBLE (-3225 2550);
FORCEPROP 2 LAST BOM_COST SYS_CLOCK
J 0
(-3175 2725);
DISPLAY 1.361702 (-3175 2725);
PAINT ORANGE (-3175 2725);
DISPLAY INVISIBLE (-3175 2725);
FORCEPROP 2 LAST SEC 1
J 0
(-3175 2775);
DISPLAY 0.680851 (-3175 2775);
PAINT MONO (-3175 2775);
DISPLAY INVISIBLE (-3175 2775);
FORCEPROP 2 LAST CDS_LOCATION R6P21
J 0
(-3180 2675);
DISPLAY 0.617021 (-3180 2675);
PAINT AQUA (-3180 2675);
DISPLAY INVISIBLE (-3180 2675);
FORCEPROP 1 LAST PATH I80
J 0
(-3175 2725);
DISPLAY 0.978723 (-3175 2725);
PAINT WHITE (-3175 2725);
DISPLAY INVISIBLE (-3175 2725);
FORCEPROP 2 LAST ROOM DB1200ZL
J 0
(-3175 2725);
DISPLAY 1.361702 (-3175 2725);
PAINT ORANGE (-3175 2725);
DISPLAY INVISIBLE (-3175 2725);
FORCEPROP 2 LAST SEC_TYPE 0402
J 0
(-3175 2775);
DISPLAY 1.021277 (-3175 2775);
PAINT ORANGE (-3175 2775);
DISPLAY INVISIBLE (-3175 2775);
FORCEADD RES..2
(-2850 2550);
FORCEPROP 1 LASTPIN (-2850 2450) $PN 2
J 0
(-2845 2460);
DISPLAY 0.617021 (-2845 2460);
PAINT ORANGE (-2845 2460);
FORCEPROP 1 LAST MATERIAL CHIP
J 0
(-2810 2475);
DISPLAY 0.617021 (-2810 2475);
PAINT SKYBLUE (-2810 2475);
FORCEPROP 1 LAST PACK_TYPE 0402
J 0
(-2810 2375);
DISPLAY 0.617021 (-2810 2375);
PAINT SKYBLUE (-2810 2375);
FORCEPROP 1 LAST WATTAGE 1/16W
J 0
(-2810 2525);
DISPLAY 0.617021 (-2810 2525);
PAINT SKYBLUE (-2810 2525);
FORCEPROP 1 LASTPIN (-2850 2650) $PN 1
J 0
(-2845 2612);
DISPLAY 0.617021 (-2845 2612);
PAINT ORANGE (-2845 2612);
FORCEPROP 1 LAST TOLERANCE 1%
J 0
(-2805 2575);
DISPLAY 0.617021 (-2805 2575);
PAINT SKYBLUE (-2805 2575);
FORCEPROP 1 LAST VALUE 1.00K
J 0
(-2805 2625);
DISPLAY 0.617021 (-2805 2625);
PAINT SKYBLUE (-2805 2625);
FORCEPROP 1 LAST LOCATION R6P20
J 0
(-2805 2675);
DISPLAY 0.617021 (-2805 2675);
PAINT AQUA (-2805 2675);
FORCEPROP 1 LAST PART_NUMBER G21796-026
J 0
(-2810 2425);
DISPLAY 0.617021 (-2810 2425);
PAINT BLUE (-2810 2425);
FORCEPROP 2 LAST CDS_LIB mstr_discrete
J 0
(-2850 2550);
PAINT ORANGE (-2850 2550);
DISPLAY INVISIBLE (-2850 2550);
FORCEPROP 2 LAST ROOM DB1200ZL
J 0
(-2800 2725);
DISPLAY 1.361702 (-2800 2725);
PAINT ORANGE (-2800 2725);
DISPLAY INVISIBLE (-2800 2725);
FORCEPROP 1 LAST PATH I81
J 0
(-2800 2725);
DISPLAY 0.978723 (-2800 2725);
PAINT WHITE (-2800 2725);
DISPLAY INVISIBLE (-2800 2725);
FORCEPROP 2 LAST CDS_LOCATION R6P20
J 0
(-2805 2675);
DISPLAY 0.617021 (-2805 2675);
PAINT AQUA (-2805 2675);
DISPLAY INVISIBLE (-2805 2675);
FORCEPROP 2 LAST SEC 1
J 0
(-2800 2775);
DISPLAY 0.680851 (-2800 2775);
PAINT MONO (-2800 2775);
DISPLAY INVISIBLE (-2800 2775);
FORCEPROP 2 LAST BOM_COST SYS_CLOCK
J 0
(-2800 2725);
DISPLAY 1.361702 (-2800 2725);
PAINT ORANGE (-2800 2725);
DISPLAY INVISIBLE (-2800 2725);
FORCEPROP 2 LAST SEC_TYPE 0402
J 0
(-2800 2775);
DISPLAY 1.021277 (-2800 2775);
PAINT ORANGE (-2800 2775);
DISPLAY INVISIBLE (-2800 2775);
FORCEADD RES..1
(-1350 4875);
FORCEPROP 1 LAST VALUE 33.2
J 2
(-1400 4825);
DISPLAY 0.617021 (-1400 4825);
PAINT SKYBLUE (-1400 4825);
FORCEPROP 1 LAST LOCATION R4D36
J 0
(-1450 4900);
DISPLAY 0.617021 (-1450 4900);
PAINT AQUA (-1450 4900);
FORCEPROP 1 LAST TOLERANCE 1%
J 0
(-1300 4825);
DISPLAY 0.617021 (-1300 4825);
PAINT SKYBLUE (-1300 4825);
FORCEPROP 1 LAST PACK_TYPE 0402
J 0
(-1200 4825);
DISPLAY 0.617021 (-1200 4825);
PAINT SKYBLUE (-1200 4825);
FORCEPROP 1 LAST PART_NUMBER G21796-074
J 0
(-1275 4900);
DISPLAY 0.617021 (-1275 4900);
PAINT BLUE (-1275 4900);
FORCEPROP 1 LAST WATTAGE 1/16W
J 2
(-1375 4725);
DISPLAY 0.617021 (-1375 4725);
PAINT SKYBLUE (-1375 4725);
DISPLAY INVISIBLE (-1375 4725);
FORCEPROP 1 LAST MATERIAL CHIP
J 0
(-1350 4725);
DISPLAY 0.617021 (-1350 4725);
PAINT SKYBLUE (-1350 4725);
DISPLAY INVISIBLE (-1350 4725);
FORCEPROP 1 LASTPIN (-1450 4875) $PN 1
J 0
(-1438 4887);
DISPLAY 0.787234 (-1438 4887);
PAINT ORANGE (-1438 4887);
DISPLAY INVISIBLE (-1438 4887);
FORCEPROP 1 LASTPIN (-1250 4875) $PN 2
J 0
(-1288 4887);
DISPLAY 0.787234 (-1288 4887);
PAINT ORANGE (-1288 4887);
DISPLAY INVISIBLE (-1288 4887);
FORCEPROP 1 LAST PATH I82
J 0
(-1400 5025);
DISPLAY 0.978723 (-1400 5025);
PAINT WHITE (-1400 5025);
DISPLAY INVISIBLE (-1400 5025);
FORCEPROP 2 LAST CDS_LOCATION R4D36
J 0
(-1450 4900);
DISPLAY 0.617021 (-1450 4900);
PAINT AQUA (-1450 4900);
DISPLAY INVISIBLE (-1450 4900);
FORCEPROP 2 LAST $SEC 1
J 0
(-1400 5075);
PAINT MONO (-1400 5075);
DISPLAY INVISIBLE (-1400 5075);
FORCEPROP 2 LAST CDS_SEC 1
J 0
(-1400 5075);
PAINT MONO (-1400 5075);
DISPLAY INVISIBLE (-1400 5075);
FORCEPROP 2 LAST CDS_LIB mstr_discrete
J 0
(-1350 4875);
PAINT ORANGE (-1350 4875);
DISPLAY INVISIBLE (-1350 4875);
FORCEPROP 2 LAST ROOM DB1200ZL
J 0
(-1275 5000);
DISPLAY 1.021277 (-1275 5000);
PAINT ORANGE (-1275 5000);
DISPLAY INVISIBLE (-1275 5000);
FORCEPROP 2 LAST BOM_COST SYS_CLOCK
J 0
(-1275 5100);
DISPLAY 1.021277 (-1275 5100);
PAINT ORANGE (-1275 5100);
DISPLAY INVISIBLE (-1275 5100);
FORCEADD OFFPAGE..6
(-2300 4875);
FORCEPROP 2 LAST $XR0 101 
J 0
(-2610 4875);
DISPLAY 0.638298 (-2610 4875);
PAINT MONO (-2610 4875);
FORCEPROP 2 LAST $XR1 111 
J 0
(-2730 4875);
DISPLAY 0.638298 (-2730 4875);
PAINT MONO (-2730 4875);
FORCEPROP 2 LAST $XR2 138 
J 0
(-2850 4875);
DISPLAY 0.638298 (-2850 4875);
PAINT MONO (-2850 4875);
FORCEPROP 2 LAST $XR3 156 
J 0
(-2970 4875);
DISPLAY 0.638298 (-2970 4875);
PAINT MONO (-2970 4875);
FORCEPROP 2 LAST $XR4 159 
J 0
(-3090 4875);
DISPLAY 0.638298 (-3090 4875);
PAINT MONO (-3090 4875);
FORCEPROP 2 LAST $XR5 247 
J 0
(-3090 4875);
DISPLAY 0.638298 (-3090 4875);
PAINT MONO (-3090 4875);
FORCEPROP 2 LAST PATH I83
J 0
(-2250 4950);
DISPLAY 1.021277 (-2250 4950);
PAINT ORANGE (-2250 4950);
DISPLAY INVISIBLE (-2250 4950);
FORCEPROP 1 LAST COMMENT_BODY TRUE
J 0
(-2200 4800);
DISPLAY 0.872340 (-2200 4800);
PAINT GREEN (-2200 4800);
DISPLAY INVISIBLE (-2200 4800);
FORCEPROP 2 LAST CDS_LIB mstr_standard
J 0
(-2300 4875);
PAINT ORANGE (-2300 4875);
DISPLAY INVISIBLE (-2300 4875);
FORCEPROP 1 LAST OFFPAGE TRUE
J 0
(-1975 4750);
DISPLAY 0.872340 (-1975 4750);
PAINT GREEN (-1975 4750);
DISPLAY INVISIBLE (-1975 4750);
FORCEADD OFFPAGE..3
(-175 4875);
FORCEPROP 2 LAST $XR0 102 
J 0
(39 4875);
DISPLAY 0.638298 (39 4875);
PAINT MONO (39 4875);
FORCEPROP 1 LAST COMMENT_BODY TRUE
J 0
(-225 4775);
DISPLAY 0.872340 (-225 4775);
PAINT GREEN (-225 4775);
DISPLAY INVISIBLE (-225 4775);
FORCEPROP 2 LAST PATH I84
J 0
(-125 4950);
DISPLAY 1.021277 (-125 4950);
PAINT ORANGE (-125 4950);
DISPLAY INVISIBLE (-125 4950);
FORCEPROP 2 LAST CDS_LIB mstr_standard
J 0
(-175 4875);
PAINT ORANGE (-175 4875);
DISPLAY INVISIBLE (-175 4875);
FORCEPROP 1 LAST OFFPAGE TRUE
J 0
(150 4750);
DISPLAY 0.872340 (150 4750);
PAINT GREEN (150 4750);
DISPLAY INVISIBLE (150 4750);
FORCEADD OFFPAGE..1
(-2300 4725);
FORCEPROP 2 LAST $XR0 138 
J 0
(-2552 4725);
DISPLAY 0.638298 (-2552 4725);
PAINT MONO (-2552 4725);
FORCEPROP 2 LAST $XR1 159 
J 0
(-2672 4725);
DISPLAY 0.638298 (-2672 4725);
PAINT MONO (-2672 4725);
FORCEPROP 2 LAST $XR2 101 
J 0
(-2792 4725);
DISPLAY 0.638298 (-2792 4725);
PAINT MONO (-2792 4725);
FORCEPROP 2 LAST $XR3 111 
J 0
(-2912 4725);
DISPLAY 0.638298 (-2912 4725);
PAINT MONO (-2912 4725);
FORCEPROP 2 LAST $XR4 156 
J 0
(-3032 4725);
DISPLAY 0.638298 (-3032 4725);
PAINT MONO (-3032 4725);
FORCEPROP 2 LAST $XR5 247 
J 0
(-3032 4725);
DISPLAY 0.638298 (-3032 4725);
PAINT MONO (-3032 4725);
FORCEPROP 2 LAST PATH I85
J 0
(-2250 4800);
DISPLAY 1.021277 (-2250 4800);
PAINT ORANGE (-2250 4800);
DISPLAY INVISIBLE (-2250 4800);
FORCEPROP 1 LAST COMMENT_BODY TRUE
J 0
(-2175 4625);
DISPLAY 0.872340 (-2175 4625);
PAINT GREEN (-2175 4625);
DISPLAY INVISIBLE (-2175 4625);
FORCEPROP 2 LAST CDS_LIB mstr_standard
J 0
(-2300 4725);
PAINT ORANGE (-2300 4725);
DISPLAY INVISIBLE (-2300 4725);
FORCEPROP 1 LAST OFFPAGE TRUE
J 0
(-1975 4600);
DISPLAY 0.872340 (-1975 4600);
PAINT GREEN (-1975 4600);
DISPLAY INVISIBLE (-1975 4600);
FORCEADD OFFPAGE..2
(-175 4725);
FORCEPROP 2 LAST $XR0 102 
J 0
(14 4725);
DISPLAY 0.638298 (14 4725);
PAINT MONO (14 4725);
FORCEPROP 1 LAST COMMENT_BODY TRUE
J 0
(-220 4630);
DISPLAY 0.872340 (-220 4630);
PAINT GREEN (-220 4630);
DISPLAY INVISIBLE (-220 4630);
FORCEPROP 2 LAST CDS_LIB mstr_standard
J 0
(-175 4725);
PAINT ORANGE (-175 4725);
DISPLAY INVISIBLE (-175 4725);
FORCEPROP 2 LAST PATH I86
J 0
(0 4800);
DISPLAY 1.021277 (0 4800);
PAINT ORANGE (0 4800);
DISPLAY INVISIBLE (0 4800);
FORCEPROP 1 LAST OFFPAGE TRUE
J 0
(150 4600);
DISPLAY 0.872340 (150 4600);
PAINT GREEN (150 4600);
DISPLAY INVISIBLE (150 4600);
FORCEADD RES..1
(-1350 4725);
FORCEPROP 1 LAST LOCATION R4D37
J 0
(-1450 4750);
DISPLAY 0.617021 (-1450 4750);
PAINT AQUA (-1450 4750);
FORCEPROP 1 LAST VALUE 33.2
J 2
(-1400 4675);
DISPLAY 0.617021 (-1400 4675);
PAINT SKYBLUE (-1400 4675);
FORCEPROP 1 LAST TOLERANCE 1%
J 0
(-1300 4675);
DISPLAY 0.617021 (-1300 4675);
PAINT SKYBLUE (-1300 4675);
FORCEPROP 1 LAST PACK_TYPE 0402
J 0
(-1200 4675);
DISPLAY 0.617021 (-1200 4675);
PAINT SKYBLUE (-1200 4675);
FORCEPROP 1 LAST PART_NUMBER G21796-074
J 0
(-1275 4750);
DISPLAY 0.617021 (-1275 4750);
PAINT BLUE (-1275 4750);
FORCEPROP 1 LAST WATTAGE 1/16W
J 2
(-1375 4575);
DISPLAY 0.617021 (-1375 4575);
PAINT SKYBLUE (-1375 4575);
DISPLAY INVISIBLE (-1375 4575);
FORCEPROP 1 LAST MATERIAL CHIP
J 0
(-1350 4575);
DISPLAY 0.617021 (-1350 4575);
PAINT SKYBLUE (-1350 4575);
DISPLAY INVISIBLE (-1350 4575);
FORCEPROP 2 LAST CDS_LOCATION R4D37
J 0
(-1450 4750);
DISPLAY 0.617021 (-1450 4750);
PAINT AQUA (-1450 4750);
DISPLAY INVISIBLE (-1450 4750);
FORCEPROP 1 LASTPIN (-1450 4725) $PN 1
J 0
(-1438 4737);
DISPLAY 0.787234 (-1438 4737);
PAINT ORANGE (-1438 4737);
DISPLAY INVISIBLE (-1438 4737);
FORCEPROP 2 LAST CDS_LIB mstr_discrete
J 0
(-1350 4725);
PAINT ORANGE (-1350 4725);
DISPLAY INVISIBLE (-1350 4725);
FORCEPROP 1 LASTPIN (-1250 4725) $PN 2
J 0
(-1288 4737);
DISPLAY 0.787234 (-1288 4737);
PAINT ORANGE (-1288 4737);
DISPLAY INVISIBLE (-1288 4737);
FORCEPROP 1 LAST PATH I87
J 0
(-1400 4875);
DISPLAY 0.978723 (-1400 4875);
PAINT WHITE (-1400 4875);
DISPLAY INVISIBLE (-1400 4875);
FORCEPROP 2 LAST $SEC 1
J 0
(-1400 4925);
PAINT MONO (-1400 4925);
DISPLAY INVISIBLE (-1400 4925);
FORCEPROP 2 LAST CDS_SEC 1
J 0
(-1400 4925);
PAINT MONO (-1400 4925);
DISPLAY INVISIBLE (-1400 4925);
FORCEPROP 2 LAST ROOM DB1200ZL
J 0
(-1275 4850);
DISPLAY 1.021277 (-1275 4850);
PAINT ORANGE (-1275 4850);
DISPLAY INVISIBLE (-1275 4850);
FORCEPROP 2 LAST BOM_COST SYS_CLOCK
J 0
(-1275 4950);
DISPLAY 1.021277 (-1275 4950);
PAINT ORANGE (-1275 4950);
DISPLAY INVISIBLE (-1275 4950);
FORCEADD OFFPAGE..1
(-1175 3075);
FORCEPROP 2 LAST $XR0 102 
J 0
(-1427 3075);
DISPLAY 0.638298 (-1427 3075);
PAINT MONO (-1427 3075);
FORCEPROP 2 LAST $XR1 191 
J 0
(-1547 3075);
DISPLAY 0.638298 (-1547 3075);
PAINT MONO (-1547 3075);
FORCEPROP 1 LAST COMMENT_BODY TRUE
J 0
(-1050 2975);
DISPLAY 1.404255 (-1050 2975);
PAINT PEACH (-1050 2975);
DISPLAY INVISIBLE (-1050 2975);
FORCEPROP 2 LAST CDS_LIB mstr_standard
J 0
(-1175 3075);
PAINT ORANGE (-1175 3075);
DISPLAY INVISIBLE (-1175 3075);
FORCEPROP 2 LAST PATH I89
J 0
(-1125 3150);
DISPLAY 1.021277 (-1125 3150);
PAINT ORANGE (-1125 3150);
DISPLAY INVISIBLE (-1125 3150);
FORCEPROP 1 LAST OFFPAGE TRUE
J 0
(-850 2950);
PAINT GREEN (-850 2950);
DISPLAY INVISIBLE (-850 2950);
FORCEADD P3V3..1
(1475 1350);
FORCEPROP 3 LASTPIN (1475 1300) SIG_NAME P3V3\g
J 0
(1485 1310);
DISPLAY 0.659574 (1485 1310);
PAINT MONO (1485 1310);
DISPLAY INVISIBLE (1485 1310);
FORCEPROP 1 LAST HDL_POWER P3V3
J 0
(1150 1225);
DISPLAY 0.872340 (1150 1225);
PAINT ORANGE (1150 1225);
DISPLAY INVISIBLE (1150 1225);
FORCEPROP 1 LAST PATH I9
J 0
(1520 1352);
DISPLAY 0.340426 (1520 1352);
PAINT GREEN (1520 1352);
DISPLAY INVISIBLE (1520 1352);
FORCEPROP 1 LAST VOLTAGE 3.3V
J 0
(1430 1307);
DISPLAY 0.340426 (1430 1307);
PAINT SKYBLUE (1430 1307);
DISPLAY INVISIBLE (1430 1307);
FORCEPROP 1 LAST SIZE 1B
J 0
(1520 1372);
DISPLAY 0.340426 (1520 1372);
PAINT GREEN (1520 1372);
DISPLAY INVISIBLE (1520 1372);
FORCEPROP 2 LAST CDS_LIB mstr_symbols
J 0
(1475 1350);
PAINT ORANGE (1475 1350);
DISPLAY INVISIBLE (1475 1350);
FORCEPROP 1 LAST BODY_TYPE PLUMBING
J 0
(1430 1307);
DISPLAY 0.340426 (1430 1307);
PAINT GREEN (1430 1307);
DISPLAY INVISIBLE (1430 1307);
FORCEADD OFFPAGE..1
(-1175 2775);
FORCEPROP 2 LAST $XR0 102 
J 0
(-1427 2775);
DISPLAY 0.638298 (-1427 2775);
PAINT MONO (-1427 2775);
FORCEPROP 2 LAST $XR1 191 
J 0
(-1547 2775);
DISPLAY 0.638298 (-1547 2775);
PAINT MONO (-1547 2775);
FORCEPROP 1 LAST COMMENT_BODY TRUE
J 0
(-1050 2675);
DISPLAY 1.404255 (-1050 2675);
PAINT PEACH (-1050 2675);
DISPLAY INVISIBLE (-1050 2675);
FORCEPROP 2 LAST CDS_LIB mstr_standard
J 0
(-1175 2775);
PAINT ORANGE (-1175 2775);
DISPLAY INVISIBLE (-1175 2775);
FORCEPROP 2 LAST PATH I90
J 0
(-1125 2850);
DISPLAY 1.021277 (-1125 2850);
PAINT ORANGE (-1125 2850);
DISPLAY INVISIBLE (-1125 2850);
FORCEPROP 1 LAST OFFPAGE TRUE
J 0
(-850 2650);
PAINT GREEN (-850 2650);
DISPLAY INVISIBLE (-850 2650);
FORCEADD RES..2
R 2
(-425 1150);
FORCEPROP 1 LAST PACK_TYPE 0402
J 2
(-465 975);
DISPLAY 0.617021 (-465 975);
PAINT SKYBLUE (-465 975);
FORCEPROP 1 LAST WATTAGE 1/16W
J 2
(-465 1125);
DISPLAY 0.617021 (-465 1125);
PAINT SKYBLUE (-465 1125);
FORCEPROP 1 LAST MATERIAL CHIP
J 2
(-465 1075);
DISPLAY 0.617021 (-465 1075);
PAINT SKYBLUE (-465 1075);
FORCEPROP 1 LAST TOLERANCE 1%
J 2
(-470 1175);
DISPLAY 0.617021 (-470 1175);
PAINT SKYBLUE (-470 1175);
FORCEPROP 1 LAST VALUE 4.75K
J 2
(-470 1225);
DISPLAY 0.617021 (-470 1225);
PAINT SKYBLUE (-470 1225);
FORCEPROP 1 LAST PART_NUMBER G21796-072
J 2
(-465 1025);
DISPLAY 0.617021 (-465 1025);
PAINT BLUE (-465 1025);
FORCEPROP 1 LAST LOCATION R6P48
J 2
(-470 1275);
DISPLAY 0.617021 (-470 1275);
PAINT AQUA (-470 1275);
FORCEPROP 1 LASTPIN (-425 1050) $PN 2
J 2
(-430 1060);
DISPLAY 0.617021 (-430 1060);
PAINT ORANGE (-430 1060);
FORCEPROP 1 LASTPIN (-425 1250) $PN 1
J 2
(-430 1212);
DISPLAY 0.617021 (-430 1212);
PAINT ORANGE (-430 1212);
FORCEPROP 2 LAST CDS_LIB mstr_discrete
J 0
(-425 1150);
PAINT ORANGE (-425 1150);
DISPLAY INVISIBLE (-425 1150);
FORCEPROP 2 LAST ROOM DB1200ZL
J 0
(-450 1250);
PAINT MONO (-450 1250);
DISPLAY INVISIBLE (-450 1250);
FORCEPROP 1 LAST PATH I91
J 2
(-475 1325);
DISPLAY 0.978723 (-475 1325);
PAINT WHITE (-475 1325);
DISPLAY INVISIBLE (-475 1325);
FORCEPROP 2 LAST SEC 1
J 0
(-475 1375);
DISPLAY 0.680851 (-475 1375);
PAINT MONO (-475 1375);
DISPLAY INVISIBLE (-475 1375);
FORCEPROP 2 LAST BOM_COST SYS_CLOCK
J 0
(-450 1300);
PAINT MONO (-450 1300);
DISPLAY INVISIBLE (-450 1300);
FORCEPROP 2 LAST SEC_TYPE 0402
J 0
(-475 1375);
DISPLAY 1.021277 (-475 1375);
PAINT ORANGE (-475 1375);
DISPLAY INVISIBLE (-475 1375);
FORCEPROP 2 LAST SIGNAL_MODEL DEFAULT_RESISTOR_47000OHM_2_1
J 0
(-475 1375);
PAINT MONO (-475 1375);
DISPLAY INVISIBLE (-475 1375);
FORCEADD RES..2
R 2
(-125 1150);
FORCEPROP 1 LAST PACK_TYPE 0402
J 2
(-165 975);
DISPLAY 0.617021 (-165 975);
PAINT SKYBLUE (-165 975);
FORCEPROP 1 LAST WATTAGE 1/16W
J 2
(-165 1125);
DISPLAY 0.617021 (-165 1125);
PAINT SKYBLUE (-165 1125);
FORCEPROP 1 LAST MATERIAL CHIP
J 2
(-165 1075);
DISPLAY 0.617021 (-165 1075);
PAINT SKYBLUE (-165 1075);
FORCEPROP 1 LAST VALUE 4.75K
J 2
(-170 1225);
DISPLAY 0.617021 (-170 1225);
PAINT SKYBLUE (-170 1225);
FORCEPROP 1 LAST PART_NUMBER G21796-072
J 2
(-165 1025);
DISPLAY 0.617021 (-165 1025);
PAINT BLUE (-165 1025);
FORCEPROP 1 LAST LOCATION R4D69
J 2
(-170 1275);
DISPLAY 0.617021 (-170 1275);
PAINT AQUA (-170 1275);
FORCEPROP 1 LAST TOLERANCE 1%
J 2
(-170 1175);
DISPLAY 0.617021 (-170 1175);
PAINT SKYBLUE (-170 1175);
FORCEPROP 1 LASTPIN (-125 1050) $PN 2
J 2
(-130 1060);
DISPLAY 0.617021 (-130 1060);
PAINT ORANGE (-130 1060);
FORCEPROP 1 LASTPIN (-125 1250) $PN 1
J 2
(-130 1212);
DISPLAY 0.617021 (-130 1212);
PAINT ORANGE (-130 1212);
FORCEPROP 2 LAST CDS_LIB mstr_discrete
J 0
(-125 1150);
PAINT ORANGE (-125 1150);
DISPLAY INVISIBLE (-125 1150);
FORCEPROP 2 LAST ROOM DB1200ZL
J 0
(-150 1250);
PAINT MONO (-150 1250);
DISPLAY INVISIBLE (-150 1250);
FORCEPROP 2 LAST SEC 1
J 0
(-175 1375);
DISPLAY 0.680851 (-175 1375);
PAINT MONO (-175 1375);
DISPLAY INVISIBLE (-175 1375);
FORCEPROP 1 LAST PATH I93
J 2
(-175 1325);
DISPLAY 0.978723 (-175 1325);
PAINT WHITE (-175 1325);
DISPLAY INVISIBLE (-175 1325);
FORCEPROP 2 LAST SEC_TYPE 0402
J 0
(-175 1375);
DISPLAY 1.021277 (-175 1375);
PAINT ORANGE (-175 1375);
DISPLAY INVISIBLE (-175 1375);
FORCEPROP 2 LAST SIGNAL_MODEL DEFAULT_RESISTOR_47000OHM_2_1
J 0
(-175 1375);
PAINT MONO (-175 1375);
DISPLAY INVISIBLE (-175 1375);
FORCEPROP 2 LAST BOM_COST SYS_CLOCK
J 0
(-150 1300);
PAINT MONO (-150 1300);
DISPLAY INVISIBLE (-150 1300);
FORCEADD RES..2
R 2
(200 1150);
FORCEPROP 1 LAST PART_NUMBER G21796-072
J 2
(160 1025);
DISPLAY 0.617021 (160 1025);
PAINT BLUE (160 1025);
FORCEPROP 1 LAST PACK_TYPE 0402
J 2
(160 975);
DISPLAY 0.617021 (160 975);
PAINT SKYBLUE (160 975);
FORCEPROP 1 LAST MATERIAL CHIP
J 2
(160 1075);
DISPLAY 0.617021 (160 1075);
PAINT SKYBLUE (160 1075);
FORCEPROP 1 LAST TOLERANCE 1%
J 2
(155 1175);
DISPLAY 0.617021 (155 1175);
PAINT SKYBLUE (155 1175);
FORCEPROP 1 LAST WATTAGE 1/16W
J 2
(160 1125);
DISPLAY 0.617021 (160 1125);
PAINT SKYBLUE (160 1125);
FORCEPROP 1 LAST VALUE 4.75K
J 2
(155 1225);
DISPLAY 0.617021 (155 1225);
PAINT SKYBLUE (155 1225);
FORCEPROP 1 LASTPIN (200 1050) $PN 2
J 2
(195 1060);
DISPLAY 0.617021 (195 1060);
PAINT ORANGE (195 1060);
FORCEPROP 1 LASTPIN (200 1250) $PN 1
J 2
(195 1212);
DISPLAY 0.617021 (195 1212);
PAINT ORANGE (195 1212);
FORCEPROP 1 LAST LOCATION R4D70
J 2
(155 1275);
DISPLAY 0.617021 (155 1275);
PAINT AQUA (155 1275);
FORCEPROP 2 LAST CDS_LIB mstr_discrete
J 0
(200 1150);
PAINT ORANGE (200 1150);
DISPLAY INVISIBLE (200 1150);
FORCEPROP 2 LAST ROOM DB1200ZL
J 0
(175 1250);
PAINT MONO (175 1250);
DISPLAY INVISIBLE (175 1250);
FORCEPROP 2 LAST SEC 1
J 0
(150 1375);
DISPLAY 0.680851 (150 1375);
PAINT MONO (150 1375);
DISPLAY INVISIBLE (150 1375);
FORCEPROP 1 LAST PATH I94
J 2
(150 1325);
DISPLAY 0.978723 (150 1325);
PAINT WHITE (150 1325);
DISPLAY INVISIBLE (150 1325);
FORCEPROP 2 LAST SEC_TYPE 0402
J 0
(150 1375);
DISPLAY 1.021277 (150 1375);
PAINT ORANGE (150 1375);
DISPLAY INVISIBLE (150 1375);
FORCEPROP 2 LAST BOM_COST SYS_CLOCK
J 0
(175 1300);
PAINT MONO (175 1300);
DISPLAY INVISIBLE (175 1300);
FORCEPROP 2 LAST SIGNAL_MODEL DEFAULT_RESISTOR_47000OHM_2_1
J 0
(150 1375);
PAINT MONO (150 1375);
DISPLAY INVISIBLE (150 1375);
FORCEADD P3V3..1
(-425 1450);
FORCEPROP 3 LASTPIN (-425 1400) SIG_NAME P3V3\g
J 0
(-415 1410);
DISPLAY 0.659574 (-415 1410);
PAINT MONO (-415 1410);
DISPLAY INVISIBLE (-415 1410);
FORCEPROP 1 LAST HDL_POWER P3V3
J 0
(-750 1325);
DISPLAY 0.872340 (-750 1325);
PAINT ORANGE (-750 1325);
DISPLAY INVISIBLE (-750 1325);
FORCEPROP 1 LAST BODY_TYPE PLUMBING
J 0
(-470 1407);
DISPLAY 0.340426 (-470 1407);
PAINT GREEN (-470 1407);
DISPLAY INVISIBLE (-470 1407);
FORCEPROP 1 LAST VOLTAGE 3.3V
J 0
(-470 1407);
DISPLAY 0.340426 (-470 1407);
PAINT SKYBLUE (-470 1407);
DISPLAY INVISIBLE (-470 1407);
FORCEPROP 2 LAST CDS_LIB mstr_symbols
J 0
(-425 1450);
PAINT ORANGE (-425 1450);
DISPLAY INVISIBLE (-425 1450);
FORCEPROP 1 LAST SIZE 1B
J 0
(-380 1472);
DISPLAY 0.340426 (-380 1472);
PAINT GREEN (-380 1472);
DISPLAY INVISIBLE (-380 1472);
FORCEPROP 1 LAST PATH I95
J 0
(-380 1452);
DISPLAY 0.340426 (-380 1452);
PAINT GREEN (-380 1452);
DISPLAY INVISIBLE (-380 1452);
FORCEADD OFFPAGE..2
(775 950);
FORCEPROP 2 LAST $XR0 191 
J 0
(964 950);
DISPLAY 0.638298 (964 950);
PAINT MONO (964 950);
FORCEPROP 2 LAST $XR1 102 
J 0
(1084 950);
DISPLAY 0.638298 (1084 950);
PAINT MONO (1084 950);
FORCEPROP 1 LAST COMMENT_BODY TRUE
J 0
(730 855);
DISPLAY 0.872340 (730 855);
PAINT GREEN (730 855);
DISPLAY INVISIBLE (730 855);
FORCEPROP 2 LAST CDS_LIB mstr_standard
J 0
(775 950);
PAINT ORANGE (775 950);
DISPLAY INVISIBLE (775 950);
FORCEPROP 2 LAST PATH I96
J 0
(950 1025);
DISPLAY 1.021277 (950 1025);
PAINT ORANGE (950 1025);
DISPLAY INVISIBLE (950 1025);
FORCEPROP 1 LAST OFFPAGE TRUE
J 0
(1100 825);
DISPLAY 0.872340 (1100 825);
PAINT GREEN (1100 825);
DISPLAY INVISIBLE (1100 825);
FORCEADD OFFPAGE..2
(775 900);
FORCEPROP 2 LAST $XR0 191 
J 0
(964 900);
DISPLAY 0.638298 (964 900);
PAINT MONO (964 900);
FORCEPROP 2 LAST $XR1 102 
J 0
(1084 900);
DISPLAY 0.638298 (1084 900);
PAINT MONO (1084 900);
FORCEPROP 1 LAST COMMENT_BODY TRUE
J 0
(730 805);
DISPLAY 0.872340 (730 805);
PAINT GREEN (730 805);
DISPLAY INVISIBLE (730 805);
FORCEPROP 2 LAST CDS_LIB mstr_standard
J 0
(775 900);
PAINT ORANGE (775 900);
DISPLAY INVISIBLE (775 900);
FORCEPROP 2 LAST PATH I97
J 0
(950 975);
DISPLAY 1.021277 (950 975);
PAINT ORANGE (950 975);
DISPLAY INVISIBLE (950 975);
FORCEPROP 1 LAST OFFPAGE TRUE
J 0
(1100 775);
DISPLAY 0.872340 (1100 775);
PAINT GREEN (1100 775);
DISPLAY INVISIBLE (1100 775);
FORCEADD OFFPAGE..2
(775 850);
FORCEPROP 2 LAST $XR0 190 
J 0
(964 850);
DISPLAY 0.638298 (964 850);
PAINT MONO (964 850);
FORCEPROP 2 LAST $XR1 102 
J 0
(1084 850);
DISPLAY 0.638298 (1084 850);
PAINT MONO (1084 850);
FORCEPROP 1 LAST COMMENT_BODY TRUE
J 0
(730 755);
DISPLAY 0.872340 (730 755);
PAINT GREEN (730 755);
DISPLAY INVISIBLE (730 755);
FORCEPROP 2 LAST CDS_LIB mstr_standard
J 0
(775 850);
PAINT ORANGE (775 850);
DISPLAY INVISIBLE (775 850);
FORCEPROP 2 LAST PATH I98
J 0
(950 925);
DISPLAY 1.021277 (950 925);
PAINT ORANGE (950 925);
DISPLAY INVISIBLE (950 925);
FORCEPROP 1 LAST OFFPAGE TRUE
J 0
(1100 725);
DISPLAY 0.872340 (1100 725);
PAINT GREEN (1100 725);
DISPLAY INVISIBLE (1100 725);
FORCEADD OFFPAGE..1
(-1175 2925);
FORCEPROP 2 LAST $XR0 102 
J 0
(-1427 2925);
DISPLAY 0.638298 (-1427 2925);
PAINT MONO (-1427 2925);
FORCEPROP 2 LAST $XR1 190 
J 0
(-1547 2925);
DISPLAY 0.638298 (-1547 2925);
PAINT MONO (-1547 2925);
FORCEPROP 2 LAST PATH I99
J 0
(-1425 2975);
DISPLAY 1.021277 (-1425 2975);
PAINT ORANGE (-1425 2975);
DISPLAY INVISIBLE (-1425 2975);
FORCEPROP 1 LAST COMMENT_BODY TRUE
J 0
(-1050 2825);
DISPLAY 1.404255 (-1050 2825);
PAINT PEACH (-1050 2825);
DISPLAY INVISIBLE (-1050 2825);
FORCEPROP 2 LAST CDS_LIB mstr_standard
J 0
(-1175 2925);
PAINT MONO (-1175 2925);
DISPLAY INVISIBLE (-1175 2925);
FORCEPROP 1 LAST OFFPAGE TRUE
J 0
(-850 2800);
PAINT GREEN (-850 2800);
DISPLAY INVISIBLE (-850 2800);
FORCEADD DESIGN_NOTE..1
(2850 3100);
FORCEPROP 0 LAST L1 RC CLKS USED FOR DEBUG ONLY
J 0
(2675 2975);
DISPLAY 1.021277 (2675 2975);
PAINT ORANGE (2675 2975);
FORCEPROP 1 LAST COMMENT_BODY TRUE
J 0
(2875 3200);
DISPLAY 0.978723 (2875 3200);
PAINT ORANGE (2875 3200);
DISPLAY INVISIBLE (2875 3200);
FORCEPROP 2 LAST CDS_LIB mstr_symbols
J 0
(2850 3100);
PAINT ORANGE (2850 3100);
DISPLAY INVISIBLE (2850 3100);
FORCEADD DNS..2
(-2845 2920);
PAINT RED (-2845 2920);
FORCEPROP 1 LAST COMMENT_BODY TRUE
R 1
J 0
(-2770 2695);
DISPLAY 0.872340 (-2770 2695);
PAINT GREEN (-2770 2695);
DISPLAY INVISIBLE (-2770 2695);
FORCEPROP 2 LAST CDS_LIB mstr_misc
J 0
(-2845 2920);
PAINT ORANGE (-2845 2920);
DISPLAY INVISIBLE (-2845 2920);
FORCEADD DNS..2
(-3220 2920);
PAINT RED (-3220 2920);
FORCEPROP 1 LAST COMMENT_BODY TRUE
R 1
J 0
(-3145 2695);
DISPLAY 0.872340 (-3145 2695);
PAINT GREEN (-3145 2695);
DISPLAY INVISIBLE (-3145 2695);
FORCEPROP 2 LAST CDS_LIB mstr_misc
J 0
(-3220 2920);
PAINT ORANGE (-3220 2920);
DISPLAY INVISIBLE (-3220 2920);
FORCEADD DNS..2
(-2670 1095);
PAINT RED (-2670 1095);
FORCEPROP 1 LAST COMMENT_BODY TRUE
R 1
J 0
(-2595 870);
DISPLAY 0.872340 (-2595 870);
PAINT GREEN (-2595 870);
DISPLAY INVISIBLE (-2595 870);
FORCEPROP 2 LAST CDS_LIB mstr_misc
J 0
(-2670 1095);
PAINT ORANGE (-2670 1095);
DISPLAY INVISIBLE (-2670 1095);
FORCEADD DNS..2
(-2920 1095);
PAINT RED (-2920 1095);
FORCEPROP 1 LAST COMMENT_BODY TRUE
R 1
J 0
(-2845 870);
DISPLAY 0.872340 (-2845 870);
PAINT GREEN (-2845 870);
DISPLAY INVISIBLE (-2845 870);
FORCEPROP 2 LAST CDS_LIB mstr_misc
J 0
(-2920 1095);
PAINT ORANGE (-2920 1095);
DISPLAY INVISIBLE (-2920 1095);
FORCEADD DESIGN_NOTE..1
(-2125 1075);
PAINT PURPLE (-2125 1075);
FORCEPROP 0 LAST L2 '1' FOR HBW MODE (DEFAULT)
J 0
(-2325 900);
DISPLAY 0.808511 (-2325 900);
PAINT VIOLET (-2325 900);
FORCEPROP 0 LAST L1 '0' FOR LBW MODE
J 0
(-2325 950);
DISPLAY 0.808511 (-2325 950);
PAINT VIOLET (-2325 950);
FORCEPROP 0 LAST L3 PU & PD FOR BYPASS MODE
J 0
(-2325 850);
DISPLAY 0.808511 (-2325 850);
PAINT ORANGE (-2325 850);
FORCEPROP 2 LAST BOM_COST SYS_CLOCK
J 0
(-2325 1025);
PAINT MONO (-2325 1025);
DISPLAY INVISIBLE (-2325 1025);
FORCEPROP 2 LAST CDS_LIB mstr_symbols
J 0
(-2125 1075);
PAINT ORANGE (-2125 1075);
DISPLAY INVISIBLE (-2125 1075);
FORCEPROP 1 LAST COMMENT_BODY TRUE
J 0
(-2100 1175);
DISPLAY 1.319149 (-2100 1175);
PAINT GREEN (-2100 1175);
DISPLAY INVISIBLE (-2100 1175);
FORCEPROP 2 LAST ROOM DB1200ZL
J 0
(-2325 1025);
PAINT MONO (-2325 1025);
DISPLAY INVISIBLE (-2325 1025);
FORCEADD DESIGN_NOTE..1
(-2125 1625);
PAINT PURPLE (-2125 1625);
FORCEPROP 0 LAST L1 '0' FOR 133M MODE
J 0
(-2325 1500);
DISPLAY 0.808511 (-2325 1500);
PAINT VIOLET (-2325 1500);
FORCEPROP 0 LAST L2 '1' FOR 100M MODE
J 0
(-2325 1450);
DISPLAY 0.808511 (-2325 1450);
PAINT VIOLET (-2325 1450);
FORCEPROP 2 LAST ROOM DB1200ZL
J 0
(-2325 1575);
PAINT MONO (-2325 1575);
DISPLAY INVISIBLE (-2325 1575);
FORCEPROP 2 LAST BOM_COST SYS_CLOCK
J 0
(-2325 1575);
PAINT MONO (-2325 1575);
DISPLAY INVISIBLE (-2325 1575);
FORCEPROP 2 LAST CDS_LIB mstr_symbols
J 0
(-2125 1625);
PAINT ORANGE (-2125 1625);
DISPLAY INVISIBLE (-2125 1625);
FORCEPROP 1 LAST COMMENT_BODY TRUE
J 0
(-2100 1725);
DISPLAY 1.319149 (-2100 1725);
PAINT GREEN (-2100 1725);
DISPLAY INVISIBLE (-2100 1725);
FORCEADD INTEL_CORP_BPAGE..1
(4250 200);
FORCEPROP 1 LAST CDS_CON_LAST_MODIFIED Tue Dec 01 11:51:51 2015
J 0
(2825 525);
PAINT ORANGE (2825 525);
DISPLAY INVISIBLE (2825 525);
FORCEPROP 1 LAST CUSTOM_TXT_CDS <CURRENT_DESIGN_SHEET> OF <TOTAL_DESIGN_SHEETS>
J 0
(3750 225);
PAINT GREEN (3750 225);
FORCEPROP 1 LAST CUSTOM_TXT_CDS <CON_LAST_MODIFIED>
J 0
(2325 550);
PAINT GREEN (2325 550);
FORCEPROP 2 LAST CUSTOM_TXT_CDS <XR_PAGE_TITLE>
J 0
(-3640 5450);
DISPLAY 0.638298 (-3640 5450);
PAINT PINK (-3640 5450);
DISPLAY INVISIBLE (-3640 5450);
FORCEPROP 1 LAST SCH_TITLE DB1200ZL
J 0
(-3700 250);
DISPLAY 1.212766 (-3700 250);
PAINT ORANGE (-3700 250);
FORCEPROP 1 LAST SCH_ADDRESS2 P.O. BOX 58119
J 0
(275 275);
DISPLAY 0.617021 (275 275);
PAINT GREEN (275 275);
FORCEPROP 1 LAST SCH_ADDRESS1 2200 Mission College Blvd.
J 0
(275 325);
DISPLAY 0.617021 (275 325);
PAINT GREEN (275 325);
FORCEPROP 1 LAST SCH_ADDRESS3 Santa Clara, CA 95052-8119
J 0
(275 225);
DISPLAY 0.617021 (275 225);
PAINT GREEN (275 225);
FORCEPROP 1 LAST SCH_REV 2.420
J 0
(4000 350);
DISPLAY 0.978723 (4000 350);
PAINT YELLOW (4000 350);
FORCEPROP 1 LAST SCH_DEPT BESD
J 1
(-200 300);
DISPLAY 1.212766 (-200 300);
PAINT YELLOW (-200 300);
FORCEPROP 1 LAST SCH_NUMBER H4694802
J 0
(2950 350);
DISPLAY 1.212766 (2950 350);
PAINT YELLOW (2950 350);
FORCEPROP 2 LAST PAGE_BORDER TRUE
J 0
(-3640 5450);
DISPLAY 0.638298 (-3640 5450);
PAINT PINK (-3640 5450);
DISPLAY INVISIBLE (-3640 5450);
FORCEPROP 1 LAST COMMENT_BODY TRUE
J 0
(4262 212);
DISPLAY 0.468085 (4262 212);
PAINT GREEN (4262 212);
DISPLAY INVISIBLE (4262 212);
FORCEPROP 2 LAST CDS_LIB mstr_symbols
J 0
(4250 200);
PAINT MONO (4250 200);
DISPLAY INVISIBLE (4250 200);
FORCEPROP 2 LAST CDS_XR_PAGE_TITLE CR-102 : @BASEBOARD_FAB2_LIB.BASEBOARD_FAB2(SCH_1):PAGE102
J 0
(-3640 5450);
DISPLAY 0.638298 (-3640 5450);
PAINT PINK (-3640 5450);
DISPLAY INVISIBLE (-3640 5450);
WIRE 16 -1 (2275 750)(1975 750);
WIRE 16 -1 (2275 875)(2275 750);
WIRE 16 -1 (2575 750)(2275 750);
WIRE 16 -1 (1975 750)(1975 875);
WIRE 16 -1 (2575 875)(2575 750);
WIRE 16 -1 (2825 750)(2575 750);
WIRE 16 -1 (2825 875)(2825 750);
WIRE 16 -1 (3050 750)(2825 750);
WIRE 16 -1 (3050 875)(3050 750);
WIRE 16 -1 (3275 750)(3050 750);
WIRE 16 -1 (3275 875)(3275 750);
WIRE 16 -1 (3475 750)(3275 750);
WIRE 16 -1 (3475 875)(3475 750);
WIRE 16 -1 (3700 750)(3475 750);
WIRE 16 -1 (3700 875)(3700 750);
WIRE 16 -1 (3700 750)(3700 675);
WIRE 16 -1 (-1800 3875)(-1800 3775);
WIRE 16 -1 (-1800 3775)(-1550 3775);
WIRE 16 -1 (-1550 3775)(-1550 3875);
WIRE 16 -1 (-1550 3775)(-1550 3675);
WIRE 16 -1 (1800 1200)(1975 1200);
WIRE 16 -1 (2275 1200)(1975 1200);
WIRE 16 -1 (1975 1075)(1975 1200);
WIRE 16 -1 (2275 1075)(2275 1200);
WIRE 16 -1 (2575 1200)(2275 1200);
WIRE 16 -1 (2575 1075)(2575 1200);
WIRE 16 -1 (2825 1200)(2575 1200);
WIRE 16 -1 (2825 1075)(2825 1200);
WIRE 16 -1 (3050 1200)(2825 1200);
WIRE 16 -1 (3050 1075)(3050 1200);
WIRE 16 -1 (3275 1200)(3050 1200);
WIRE 16 -1 (3275 1075)(3275 1200);
WIRE 16 -1 (3275 1200)(3475 1200);
WIRE 16 -1 (3475 1075)(3475 1200);
WIRE 16 -1 (3700 1200)(3475 1200);
WIRE 16 -1 (3700 1075)(3700 1200);
WIRE 16 -1 (3700 1200)(3700 1325);
WIRE 16 -1 (-2525 4200)(-2800 4200);
WIRE 16 -1 (-2800 4200)(-2800 4275);
WIRE 16 -1 (-300 3525)(-825 3525);
WIRE 16 -1 (-825 3575)(-825 3525);
WIRE 16 -1 (-300 3575)(-825 3575);
WIRE 16 -1 (-825 3625)(-825 3575);
WIRE 16 -1 (-300 3625)(-825 3625);
WIRE 16 -1 (-825 3675)(-825 3625);
WIRE 16 -1 (-300 3675)(-825 3675);
WIRE 16 -1 (-825 3725)(-825 3675);
WIRE 16 -1 (-300 3725)(-825 3725);
WIRE 16 -1 (-825 3775)(-825 3725);
WIRE 16 -1 (-300 3775)(-825 3775);
WIRE 16 -1 (-825 3825)(-825 3775);
WIRE 16 -1 (-300 3825)(-825 3825);
WIRE 16 -1 (-825 3825)(-825 3950);
WIRE 16 -1 (-2925 3475)(-3125 3475);
WIRE 16 -1 (-3125 3475)(-3125 3575);
WIRE 16 -1 (-2575 3200)(-2575 3075);
WIRE 16 -1 (-2575 3075)(-2325 3075);
WIRE 16 -1 (-2325 3075)(-2325 3200);
WIRE 16 -1 (-2325 3075)(-2325 3025);
WIRE 16 -1 (-2850 3125)(-2850 3025);
WIRE 16 -1 (-3225 3125)(-2850 3125);
WIRE 16 -1 (-3225 3025)(-3225 3125);
WIRE 16 -1 (-3225 3175)(-3225 3125);
WIRE 16 -1 (-3225 2450)(-3225 2300);
WIRE 16 -1 (-3225 2300)(-2850 2300);
WIRE 16 -1 (-2850 2300)(-2850 2450);
WIRE 16 -1 (-2850 2300)(-2850 2250);
WIRE 16 -1 (-2675 1600)(-2675 1725);
WIRE 16 -1 (-2675 1725)(-2925 1725);
WIRE 16 -1 (-2925 1725)(-2925 1825);
WIRE 16 -1 (-2925 1725)(-2925 1600);
WIRE 16 -1 (-2925 925)(-2675 925);
WIRE 16 -1 (-2925 925)(-2925 1000);
WIRE 16 -1 (-2675 1000)(-2675 925);
WIRE 16 -1 (-2675 825)(-2675 925);
WIRE 16 -1 (1000 2375)(1425 2375);
WIRE 16 -1 (1425 2375)(1425 2325);
WIRE 16 -1 (1000 2325)(1425 2325);
WIRE 16 -1 (1425 2325)(1425 2275);
WIRE 16 -1 (1000 2275)(1425 2275);
WIRE 16 -1 (1425 2275)(1425 2225);
WIRE 16 -1 (1000 2225)(1425 2225);
WIRE 16 -1 (1425 2225)(1425 2175);
WIRE 16 -1 (1000 2175)(1425 2175);
WIRE 16 -1 (1425 2175)(1425 2125);
WIRE 16 -1 (1000 2125)(1425 2125);
WIRE 16 -1 (1425 2125)(1425 2075);
WIRE 16 -1 (1000 2075)(1425 2075);
WIRE 16 -1 (1425 2075)(1425 2025);
WIRE 16 -1 (1425 2025)(1425 1850);
WIRE 16 -1 (1425 2025)(1000 2025);
WIRE 16 -1 (1475 1200)(1600 1200);
WIRE 16 -1 (1475 1300)(1475 1200);
WIRE 16 -1 (200 1250)(200 1350);
WIRE 16 -1 (-125 1350)(200 1350);
WIRE 16 -1 (-125 1250)(-125 1350);
WIRE 16 -1 (-425 1350)(-125 1350);
WIRE 16 -1 (-425 1250)(-425 1350);
WIRE 16 -1 (-425 1350)(-425 1400);
WIRE 16 -1 (-2675 1325)(-1700 1325);
FORCEPROP 0 LAST SIG_NAME FM_100M_N
J 0
(-2285 1335);
DISPLAY 0.617021 (-2285 1335);
PAINT ORANGE (-2285 1335);
WIRE 16 -1 (-2675 1400)(-2675 1325);
WIRE 16 -1 (-2675 1325)(-2675 1200);
WIRE 16 -1 (-1700 1275)(-2925 1275);
FORCEPROP 0 LAST SIG_NAME FM_HBW_BYPASS_LOWBW_N
J 0
(-2285 1285);
DISPLAY 0.617021 (-2285 1285);
PAINT ORANGE (-2285 1285);
WIRE 16 -1 (-2925 1400)(-2925 1275);
WIRE 16 -1 (-2925 1275)(-2925 1200);
WIRE 16 -1 (1000 3875)(1775 3875);
FORCEPROP 0 LAST SIG_NAME NC_DB1200ZL<2>
J 0
(1125 3885);
DISPLAY 0.617021 (1125 3885);
PAINT ORANGE (1125 3885);
FORCEPROP 2 LASTPROP $XRERR UNIQUE?
J 0
(1805 3875);
DISPLAY 0.638298 (1805 3875);
PAINT MONO (1805 3875);
DISPLAY INVISIBLE (1805 3875);
WIRE 16 -1 (1775 3775)(1000 3775);
FORCEPROP 0 LAST SIG_NAME NC_DB1200ZL<0>
J 0
(1125 3785);
DISPLAY 0.617021 (1125 3785);
PAINT ORANGE (1125 3785);
FORCEPROP 2 LASTPROP $XRERR UNIQUE?
J 0
(1805 3775);
DISPLAY 0.638298 (1805 3775);
PAINT MONO (1805 3775);
DISPLAY INVISIBLE (1805 3775);
WIRE 16 -1 (1775 3825)(1000 3825);
FORCEPROP 0 LAST SIG_NAME NC_DB1200ZL<1>
J 0
(1125 3835);
DISPLAY 0.617021 (1125 3835);
PAINT ORANGE (1125 3835);
FORCEPROP 2 LASTPROP $XRERR UNIQUE?
J 0
(1805 3825);
DISPLAY 0.638298 (1805 3825);
PAINT MONO (1805 3825);
DISPLAY INVISIBLE (1805 3825);
WIRE 16 -1 (1000 3675)(1975 3675);
FORCEPROP 2 LAST SIG_NAME CLK_100M_CPU1_RC_REFCLK1_R_DP
J 0
(1125 3685);
DISPLAY 0.617021 (1125 3685);
PAINT ORANGE (1125 3685);
WIRE 16 -1 (1000 3625)(1975 3625);
FORCEPROP 2 LAST SIG_NAME CLK_100M_CPU1_RC_REFCLK1_R_DN
J 0
(1125 3635);
DISPLAY 0.617021 (1125 3635);
PAINT ORANGE (1125 3635);
WIRE 16 -1 (1000 3575)(1975 3575);
FORCEPROP 2 LAST SIG_NAME CLK_100M_CPU1_RC_REFCLK0_R_DP
J 0
(1125 3585);
DISPLAY 0.617021 (1125 3585);
PAINT ORANGE (1125 3585);
WIRE 16 -1 (1000 3525)(1975 3525);
FORCEPROP 2 LAST SIG_NAME CLK_100M_CPU1_RC_REFCLK0_R_DN
J 0
(1125 3535);
DISPLAY 0.617021 (1125 3535);
PAINT ORANGE (1125 3535);
WIRE 16 -1 (1000 3475)(1975 3475);
FORCEPROP 2 LAST SIG_NAME CLK_100M_CPU1_PE_REFCLK_R_DP
J 0
(1125 3485);
DISPLAY 0.617021 (1125 3485);
PAINT ORANGE (1125 3485);
WIRE 16 -1 (1000 3425)(1975 3425);
FORCEPROP 2 LAST SIG_NAME CLK_100M_CPU1_PE_REFCLK_R_DN
J 0
(1125 3435);
DISPLAY 0.617021 (1125 3435);
PAINT ORANGE (1125 3435);
WIRE 16 -1 (1000 3375)(1975 3375);
FORCEPROP 2 LAST SIG_NAME CLK_100M_CPU1_BCLK2_R_DP
J 0
(1125 3385);
DISPLAY 0.617021 (1125 3385);
PAINT ORANGE (1125 3385);
WIRE 16 -1 (1000 3325)(1975 3325);
FORCEPROP 2 LAST SIG_NAME CLK_100M_CPU1_BCLK2_R_DN
J 0
(1125 3335);
DISPLAY 0.617021 (1125 3335);
PAINT ORANGE (1125 3335);
WIRE 16 -1 (1000 3275)(1975 3275);
FORCEPROP 2 LAST SIG_NAME CLK_100M_CPU1_BCLK1_R_DP
J 0
(1125 3285);
DISPLAY 0.617021 (1125 3285);
PAINT ORANGE (1125 3285);
WIRE 16 -1 (1000 3225)(1975 3225);
FORCEPROP 2 LAST SIG_NAME CLK_100M_CPU1_BCLK1_R_DN
J 0
(1125 3235);
DISPLAY 0.617021 (1125 3235);
PAINT ORANGE (1125 3235);
WIRE 16 -1 (1000 3175)(1975 3175);
FORCEPROP 2 LAST SIG_NAME CLK_100M_CPU1_BCLK0_R_DP
J 0
(1125 3185);
DISPLAY 0.617021 (1125 3185);
PAINT ORANGE (1125 3185);
WIRE 16 -1 (1000 3125)(1975 3125);
FORCEPROP 2 LAST SIG_NAME CLK_100M_CPU1_BCLK0_R_DN
J 0
(1125 3135);
DISPLAY 0.617021 (1125 3135);
PAINT ORANGE (1125 3135);
WIRE 16 -1 (1000 3075)(1975 3075);
FORCEPROP 2 LAST SIG_NAME CLK_100M_CPU0_RC_REFCLK1_R_DP
J 0
(1125 3085);
DISPLAY 0.617021 (1125 3085);
PAINT ORANGE (1125 3085);
WIRE 16 -1 (1000 3025)(1975 3025);
FORCEPROP 2 LAST SIG_NAME CLK_100M_CPU0_RC_REFCLK1_R_DN
J 0
(1125 3035);
DISPLAY 0.617021 (1125 3035);
PAINT ORANGE (1125 3035);
WIRE 16 -1 (1000 2975)(1975 2975);
FORCEPROP 2 LAST SIG_NAME CLK_100M_CPU0_RC_REFCLK0_R_DP
J 0
(1125 2985);
DISPLAY 0.617021 (1125 2985);
PAINT ORANGE (1125 2985);
WIRE 16 -1 (1000 2925)(1975 2925);
FORCEPROP 2 LAST SIG_NAME CLK_100M_CPU0_RC_REFCLK0_R_DN
J 0
(1125 2935);
DISPLAY 0.617021 (1125 2935);
PAINT ORANGE (1125 2935);
WIRE 16 -1 (1000 2875)(1975 2875);
FORCEPROP 2 LAST SIG_NAME CLK_100M_CPU0_PE_REFCLK_R_DP
J 0
(1125 2885);
DISPLAY 0.617021 (1125 2885);
PAINT ORANGE (1125 2885);
WIRE 16 -1 (1000 2825)(1975 2825);
FORCEPROP 2 LAST SIG_NAME CLK_100M_CPU0_PE_REFCLK_R_DN
J 0
(1125 2835);
DISPLAY 0.617021 (1125 2835);
PAINT ORANGE (1125 2835);
WIRE 16 -1 (1000 2775)(1975 2775);
FORCEPROP 2 LAST SIG_NAME CLK_100M_CPU0_BCLK2_R_DP
J 0
(1125 2785);
DISPLAY 0.617021 (1125 2785);
PAINT ORANGE (1125 2785);
WIRE 16 -1 (1000 2725)(1975 2725);
FORCEPROP 2 LAST SIG_NAME CLK_100M_CPU0_BCLK2_R_DN
J 0
(1125 2735);
DISPLAY 0.617021 (1125 2735);
PAINT ORANGE (1125 2735);
WIRE 16 -1 (1000 2675)(1975 2675);
FORCEPROP 2 LAST SIG_NAME CLK_100M_CPU0_BCLK1_R_DP
J 0
(1125 2685);
DISPLAY 0.617021 (1125 2685);
PAINT ORANGE (1125 2685);
WIRE 16 -1 (1000 2625)(1975 2625);
FORCEPROP 2 LAST SIG_NAME CLK_100M_CPU0_BCLK1_R_DN
J 0
(1125 2635);
DISPLAY 0.617021 (1125 2635);
PAINT ORANGE (1125 2635);
WIRE 16 -1 (1000 2575)(1975 2575);
FORCEPROP 2 LAST SIG_NAME CLK_100M_CPU0_BCLK0_R_DP
J 0
(1125 2585);
DISPLAY 0.617021 (1125 2585);
PAINT ORANGE (1125 2585);
WIRE 16 -1 (1000 2525)(1975 2525);
FORCEPROP 2 LAST SIG_NAME CLK_100M_CPU0_BCLK0_R_DN
J 0
(1125 2535);
DISPLAY 0.617021 (1125 2535);
PAINT ORANGE (1125 2535);
WIRE 16 -1 (200 1050)(200 950);
WIRE 16 -1 (200 950)(725 950);
FORCEPROP 2 LAST SIG_NAME FM_CPU0_MCP_CLK_EN_N
J 0
(240 960);
DISPLAY 0.617021 (240 960);
PAINT ORANGE (240 960);
WIRE 16 -1 (-125 900)(725 900);
FORCEPROP 2 LAST SIG_NAME FM_CPU1_MCP_CLK_EN_N
J 0
(240 910);
DISPLAY 0.617021 (240 910);
PAINT ORANGE (240 910);
WIRE 16 -1 (-125 1050)(-125 900);
WIRE 16 -1 (-425 850)(725 850);
FORCEPROP 2 LAST SIG_NAME FM_DB1200ZL_BCLKS_EN_N
J 0
(240 860);
DISPLAY 0.617021 (240 860);
PAINT ORANGE (240 860);
WIRE 16 -1 (-425 1050)(-425 850);
WIRE 16 -1 (-550 4200)(-1550 4200);
FORCEPROP 0 LAST VOLTAGE +3.3V
J 0
(-900 4250);
DISPLAY 1.021277 (-900 4250);
PAINT SKYBLUE (-900 4250);
DISPLAY INVISIBLE (-900 4250);
FORCEPROP 0 LAST SIG_NAME P3V3_DB1200_A
J 0
(-1760 4210);
DISPLAY 0.617021 (-1760 4210);
PAINT ORANGE (-1760 4210);
FORCEPROP 2 LASTPROP $XRERR UNIQUE?
J 0
(-2000 4210);
DISPLAY 0.638298 (-2000 4210);
PAINT MONO (-2000 4210);
DISPLAY INVISIBLE (-2000 4210);
WIRE 16 -1 (-550 3875)(-550 4200);
WIRE 16 -1 (-1550 4200)(-1800 4200);
WIRE 16 -1 (-1550 4075)(-1550 4200);
WIRE 16 -1 (-1800 4200)(-2325 4200);
WIRE 16 -1 (-1800 4075)(-1800 4200);
WIRE 16 -1 (-300 3875)(-550 3875);
WIRE 16 -1 (-1250 4875)(-225 4875);
FORCEPROP 2 LAST SIG_NAME SMB_HOST_STBY_LVC3_SDA_R2
J 0
(-985 4885);
DISPLAY 0.617021 (-985 4885);
PAINT ORANGE (-985 4885);
WIRE 16 -1 (-1250 4725)(-225 4725);
FORCEPROP 2 LAST SIG_NAME SMB_HOST_STBY_LVC3_SCL_R2
J 0
(-985 4735);
DISPLAY 0.617021 (-985 4735);
PAINT ORANGE (-985 4735);
WIRE 16 -1 (-2250 4875)(-1450 4875);
FORCEPROP 2 LAST SIG_NAME SMB_HOST_STBY_LVC3_SDA
J 0
(-2210 4885);
DISPLAY 0.617021 (-2210 4885);
PAINT ORANGE (-2210 4885);
WIRE 16 -1 (-2250 4725)(-1450 4725);
FORCEPROP 2 LAST SIG_NAME SMB_HOST_STBY_LVC3_SCL
J 0
(-2210 4735);
DISPLAY 0.617021 (-2210 4735);
PAINT ORANGE (-2210 4735);
WIRE 16 -1 (-525 3075)(-300 3075);
WIRE 16 -1 (-525 3025)(-525 3075);
WIRE 16 -1 (-525 3075)(-1125 3075);
FORCEPROP 2 LAST SIG_NAME FM_CPU1_MCP_CLK_EN_N
J 0
(-1125 3085);
DISPLAY 0.617021 (-1125 3085);
PAINT ORANGE (-1125 3085);
WIRE 16 -1 (-300 3025)(-525 3025);
WIRE 16 -1 (-525 3025)(-525 2975);
WIRE 16 -1 (-300 2975)(-525 2975);
WIRE 16 -1 (-300 2925)(-425 2925);
WIRE 16 -1 (-425 2875)(-425 2925);
WIRE 16 -1 (-425 2925)(-1125 2925);
FORCEPROP 0 LAST SIG_NAME FM_DB1200ZL_BCLKS_EN_N
J 0
(-1125 2935);
DISPLAY 0.617021 (-1125 2935);
PAINT ORANGE (-1125 2935);
WIRE 16 -1 (-300 2875)(-425 2875);
WIRE 16 -1 (-425 2825)(-425 2875);
WIRE 16 -1 (-300 2825)(-425 2825);
WIRE 16 -1 (-425 2825)(-425 2625);
WIRE 16 -1 (-300 2625)(-425 2625);
WIRE 16 -1 (-425 2575)(-425 2625);
WIRE 16 -1 (-300 2575)(-425 2575);
WIRE 16 -1 (-425 2525)(-425 2575);
WIRE 16 -1 (-300 2525)(-425 2525);
WIRE 16 -1 (-300 2775)(-525 2775);
WIRE 16 -1 (-525 2725)(-525 2775);
WIRE 16 -1 (-525 2775)(-1125 2775);
FORCEPROP 2 LAST SIG_NAME FM_CPU0_MCP_CLK_EN_N
J 0
(-1125 2785);
DISPLAY 0.617021 (-1125 2785);
PAINT ORANGE (-1125 2785);
WIRE 16 -1 (-300 2725)(-525 2725);
WIRE 16 -1 (-525 2675)(-525 2725);
WIRE 16 -1 (-300 2675)(-525 2675);
WIRE 16 -1 (-300 3375)(-1125 3375);
FORCEPROP 0 LAST SIG_NAME FM_DB1200_SMB_SA0
J 0
(-1125 3385);
DISPLAY 0.617021 (-1125 3385);
PAINT ORANGE (-1125 3385);
WIRE 16 -1 (-1125 3325)(-300 3325);
FORCEPROP 0 LAST SIG_NAME FM_DB1200_SMB_SA1
J 0
(-1125 3335);
DISPLAY 0.617021 (-1125 3335);
PAINT ORANGE (-1125 3335);
WIRE 16 -1 (-1125 3175)(-300 3175);
FORCEPROP 2 LAST SIG_NAME SMB_HOST_STBY_LVC3_SCL_R2
J 0
(-1125 3185);
DISPLAY 0.617021 (-1125 3185);
PAINT ORANGE (-1125 3185);
WIRE 16 -1 (-300 3225)(-1125 3225);
FORCEPROP 2 LAST SIG_NAME SMB_HOST_STBY_LVC3_SDA_R2
J 0
(-1125 3235);
DISPLAY 0.617021 (-1125 3235);
PAINT ORANGE (-1125 3235);
WIRE 16 -1 (-300 2175)(-1425 2175);
FORCEPROP 0 LAST SIG_NAME FM_HBW_BYPASS_LOWBW_N
J 0
(-1385 2185);
DISPLAY 0.617021 (-1385 2185);
PAINT ORANGE (-1385 2185);
WIRE 16 -1 (-300 2075)(-1425 2075);
FORCEPROP 0 LAST SIG_NAME FM_100M_N
J 0
(-1385 2085);
DISPLAY 0.617021 (-1385 2085);
PAINT ORANGE (-1385 2085);
WIRE 16 -1 (-300 2425)(-1425 2425);
FORCEPROP 0 LAST SIG_NAME CLK_100M_DB1200_DP
J 0
(-1385 2435);
DISPLAY 0.617021 (-1385 2435);
PAINT ORANGE (-1385 2435);
WIRE 16 -1 (-1425 2375)(-300 2375);
FORCEPROP 0 LAST SIG_NAME CLK_100M_DB1200_DN
J 0
(-1385 2385);
DISPLAY 0.617021 (-1385 2385);
PAINT ORANGE (-1385 2385);
WIRE 16 -1 (-300 2275)(-1425 2275);
FORCEPROP 0 LAST SIG_NAME FM_DB1200_PWRGD
J 0
(-1385 2285);
DISPLAY 0.617021 (-1385 2285);
PAINT ORANGE (-1385 2285);
WIRE 16 -1 (-2575 3400)(-2575 3475);
WIRE 16 -1 (-2325 3475)(-2575 3475);
WIRE 16 -1 (-2575 3475)(-2725 3475);
WIRE 16 -1 (-300 3475)(-2325 3475);
FORCEPROP 0 LAST VOLTAGE +3.3V
J 0
(-925 3525);
DISPLAY 1.021277 (-925 3525);
PAINT SKYBLUE (-925 3525);
DISPLAY INVISIBLE (-925 3525);
FORCEPROP 0 LAST SIG_NAME P3V3_DB1200_R
J 0
(-2085 3485);
DISPLAY 0.617021 (-2085 3485);
PAINT ORANGE (-2085 3485);
FORCEPROP 2 LASTPROP $XRERR UNIQUE?
J 0
(-2325 3485);
DISPLAY 0.638298 (-2325 3485);
PAINT MONO (-2325 3485);
DISPLAY INVISIBLE (-2325 3485);
WIRE 16 -1 (-2325 3400)(-2325 3475);
WIRE 16 -1 (-2850 2825)(-2850 2775);
WIRE 16 -1 (-2850 2775)(-2000 2775);
FORCEPROP 0 LAST SIG_NAME FM_DB1200_SMB_SA1
J 0
(-2525 2785);
DISPLAY 0.617021 (-2525 2785);
PAINT ORANGE (-2525 2785);
WIRE 16 -1 (-2850 2650)(-2850 2775);
WIRE 16 -1 (-3225 2725)(-2000 2725);
FORCEPROP 0 LAST SIG_NAME FM_DB1200_SMB_SA0
J 0
(-2525 2735);
DISPLAY 0.617021 (-2525 2735);
PAINT ORANGE (-2525 2735);
WIRE 16 -1 (-3225 2825)(-3225 2725);
WIRE 16 -1 (-3225 2725)(-3225 2650);
DOT 1 (-2675 925);
DOT 1 (-2925 1275);
DOT 1 (-2675 1325);
DOT 1 (-2925 1725);
DOT 1 (-3225 2725);
DOT 1 (-3225 3125);
DOT 1 (-2850 2300);
DOT 1 (-2850 2775);
DOT 1 (-2325 3075);
DOT 1 (-2575 3475);
DOT 1 (-2325 3475);
DOT 1 (-425 1350);
DOT 1 (-125 1350);
DOT 1 (-1550 3775);
DOT 1 (-525 2725);
DOT 1 (-525 2775);
DOT 1 (-525 3025);
DOT 1 (-425 2575);
DOT 1 (-425 2625);
DOT 1 (-425 2825);
DOT 1 (-425 2875);
DOT 1 (-425 2925);
DOT 1 (-525 3075);
DOT 1 (-825 3575);
DOT 1 (-825 3625);
DOT 1 (-825 3675);
DOT 1 (-825 3725);
DOT 1 (-825 3825);
DOT 1 (-825 3775);
DOT 1 (-1800 4200);
DOT 1 (-1550 4200);
DOT 1 (1425 2025);
DOT 1 (1975 1200);
DOT 1 (1425 2075);
DOT 1 (1425 2125);
DOT 1 (1425 2175);
DOT 1 (1425 2275);
DOT 1 (1425 2225);
DOT 1 (1425 2325);
DOT 1 (2275 750);
DOT 1 (2575 750);
DOT 1 (2825 750);
DOT 1 (3050 750);
DOT 1 (2275 1200);
DOT 1 (2575 1200);
DOT 1 (2825 1200);
DOT 1 (3050 1200);
DOT 1 (3275 750);
DOT 1 (3475 750);
DOT 1 (3700 750);
DOT 1 (3275 1200);
DOT 1 (3475 1200);
DOT 1 (3700 1200);
FORCENOTE
ROOM=DB1200Z
(-3700 375) 0;
DISPLAY LEFT (-3700 375);
DISPLAY 1.021277 (-3700 375);
PAINT PURPLE (-3700 375);
FORCENOTE
BOM_COST=SYS_CLOCK
(-3700 325) 0;
DISPLAY LEFT (-3700 325);
DISPLAY 1.021277 (-3700 325);
PAINT PURPLE (-3700 325);
FORCENOTE
SMBUS ADDRESS: 0XD8
(-250 1675) 0;
DISPLAY LEFT (-250 1675);
DISPLAY 1.021277 (-250 1675);
PAINT PURPLE (-250 1675);
QUIT
